FILE_TYPE = MACRO_DRAWING;
SET COLOR_WIRE YELLOW;
SET COLOR_PROP MONO;
SET COLOR_DOT WHITE;
SET COLOR_ARC YELLOW;
SET COLOR_BODY GREEN;
SET COLOR_NOTE MONO;
SET PROP_DISPLAY VALUE;
SET PAGE_NUMBER P192;
FORCEADD CAP_A..1
(-1225 1975);
FORCEPROP 1 LAST LOCATION C2P8
J 0
(-1175 2075);
DISPLAY 0.617021 (-1175 2075);
PAINT AQUA (-1175 2075);
FORCEPROP 1 LAST PART_NUMBER A36096-045
J 0
(-1175 1825);
DISPLAY 0.617021 (-1175 1825);
PAINT BLUE (-1175 1825);
FORCEPROP 1 LAST VALUE 0.01UF
J 0
(-1175 2025);
DISPLAY 0.617021 (-1175 2025);
PAINT SKYBLUE (-1175 2025);
FORCEPROP 1 LAST TOLERANCE 10%
J 0
(-1175 1925);
DISPLAY 0.617021 (-1175 1925);
PAINT SKYBLUE (-1175 1925);
FORCEPROP 1 LAST PACK_TYPE 0402V
J 0
(-1175 1775);
DISPLAY 0.617021 (-1175 1775);
PAINT SKYBLUE (-1175 1775);
FORCEPROP 1 LAST VOLTAGE 25V
J 0
(-1175 1975);
DISPLAY 0.617021 (-1175 1975);
PAINT SKYBLUE (-1175 1975);
FORCEPROP 1 LAST MATERIAL X7R
J 0
(-1175 1875);
DISPLAY 0.617021 (-1175 1875);
PAINT SKYBLUE (-1175 1875);
FORCEPROP 1 LASTPIN (-1225 2075) $PN 1
J 0
(-1215 2055);
DISPLAY 0.617021 (-1215 2055);
PAINT ORANGE (-1215 2055);
FORCEPROP 1 LASTPIN (-1225 1875) $PN 2
J 0
(-1215 1855);
DISPLAY 0.617021 (-1215 1855);
PAINT ORANGE (-1215 1855);
FORCEPROP 2 LAST ROOM CPLD
J 0
(-1175 2125);
DISPLAY 1.361702 (-1175 2125);
PAINT ORANGE (-1175 2125);
DISPLAY INVISIBLE (-1175 2125);
FORCEPROP 2 LAST CDS_LOCATION C2P8
J 0
(-1175 2075);
DISPLAY 0.617021 (-1175 2075);
PAINT AQUA (-1175 2075);
DISPLAY INVISIBLE (-1175 2075);
FORCEPROP 2 LAST BOM_COST CPLD
J 0
(-1175 2175);
DISPLAY 1.361702 (-1175 2175);
PAINT ORANGE (-1175 2175);
DISPLAY INVISIBLE (-1175 2175);
FORCEPROP 2 LAST SIGNAL_MODEL DEFAULT_CAPACITOR_10000pF_2_1
J 0
(-1175 2175);
PAINT MONO (-1175 2175);
DISPLAY INVISIBLE (-1175 2175);
FORCEPROP 2 LAST CDS_SEC 1
J 0
(-1175 2175);
PAINT MONO (-1175 2175);
DISPLAY INVISIBLE (-1175 2175);
FORCEPROP 2 LAST $SEC 1
J 0
(-1175 2175);
PAINT MONO (-1175 2175);
DISPLAY INVISIBLE (-1175 2175);
FORCEPROP 1 LAST PATH I1
J 0
(-1175 2125);
DISPLAY 0.978723 (-1175 2125);
PAINT WHITE (-1175 2125);
DISPLAY INVISIBLE (-1175 2125);
FORCEPROP 2 LAST CDS_LIB dev_discrete
J 0
(-1225 1975);
PAINT ORANGE (-1225 1975);
DISPLAY INVISIBLE (-1225 1975);
FORCEADD CAP_A..1
(-4075 1975);
FORCEPROP 1 LAST LOCATION C3R2
J 0
(-4025 2075);
DISPLAY 0.617021 (-4025 2075);
PAINT AQUA (-4025 2075);
FORCEPROP 1 LAST PART_NUMBER A36096-030
J 0
(-4025 1825);
DISPLAY 0.617021 (-4025 1825);
PAINT BLUE (-4025 1825);
FORCEPROP 1 LAST VALUE 0.1UF
J 0
(-4025 2025);
DISPLAY 0.617021 (-4025 2025);
PAINT SKYBLUE (-4025 2025);
FORCEPROP 1 LAST TOLERANCE 10%
J 0
(-4025 1925);
DISPLAY 0.617021 (-4025 1925);
PAINT SKYBLUE (-4025 1925);
FORCEPROP 1 LAST PACK_TYPE 0402V
J 0
(-4025 1775);
DISPLAY 0.617021 (-4025 1775);
PAINT SKYBLUE (-4025 1775);
FORCEPROP 1 LAST VOLTAGE 16V
J 0
(-4025 1975);
DISPLAY 0.617021 (-4025 1975);
PAINT SKYBLUE (-4025 1975);
FORCEPROP 1 LAST MATERIAL X7R
J 0
(-4025 1875);
DISPLAY 0.617021 (-4025 1875);
PAINT SKYBLUE (-4025 1875);
FORCEPROP 1 LASTPIN (-4075 2075) $PN 1
J 0
(-4065 2055);
DISPLAY 0.617021 (-4065 2055);
PAINT ORANGE (-4065 2055);
FORCEPROP 1 LASTPIN (-4075 1875) $PN 2
J 0
(-4065 1855);
DISPLAY 0.617021 (-4065 1855);
PAINT ORANGE (-4065 1855);
FORCEPROP 2 LAST ROOM CPLD
J 0
(-4025 2125);
DISPLAY 1.361702 (-4025 2125);
PAINT ORANGE (-4025 2125);
DISPLAY INVISIBLE (-4025 2125);
FORCEPROP 2 LAST SIGNAL_MODEL DEFAULT_CAPACITOR_100000pF_2_1
J 0
(-4025 2175);
PAINT MONO (-4025 2175);
DISPLAY INVISIBLE (-4025 2175);
FORCEPROP 2 LAST BOM_COST CPLD
J 0
(-4025 2175);
DISPLAY 1.361702 (-4025 2175);
PAINT ORANGE (-4025 2175);
DISPLAY INVISIBLE (-4025 2175);
FORCEPROP 2 LAST CDS_SEC 1
J 0
(-4025 2175);
PAINT MONO (-4025 2175);
DISPLAY INVISIBLE (-4025 2175);
FORCEPROP 2 LAST $SEC 1
J 0
(-4025 2175);
PAINT MONO (-4025 2175);
DISPLAY INVISIBLE (-4025 2175);
FORCEPROP 1 LAST PATH I10
J 0
(-4025 2125);
DISPLAY 0.978723 (-4025 2125);
PAINT WHITE (-4025 2125);
DISPLAY INVISIBLE (-4025 2125);
FORCEPROP 2 LAST CDS_LOCATION C3R2
J 0
(-4025 2075);
DISPLAY 0.617021 (-4025 2075);
PAINT AQUA (-4025 2075);
DISPLAY INVISIBLE (-4025 2075);
FORCEPROP 2 LAST CDS_LIB dev_discrete
J 0
(-4075 1975);
PAINT ORANGE (-4075 1975);
DISPLAY INVISIBLE (-4075 1975);
FORCEADD CAP_A..1
(-3700 1300);
FORCEPROP 1 LAST LOCATION C3P51
J 0
(-3650 1400);
DISPLAY 0.617021 (-3650 1400);
PAINT AQUA (-3650 1400);
FORCEPROP 1 LAST PART_NUMBER A36096-030
J 0
(-3650 1150);
DISPLAY 0.617021 (-3650 1150);
PAINT BLUE (-3650 1150);
FORCEPROP 1 LAST VALUE 0.1UF
J 0
(-3650 1350);
DISPLAY 0.617021 (-3650 1350);
PAINT SKYBLUE (-3650 1350);
FORCEPROP 1 LAST TOLERANCE 10%
J 0
(-3650 1250);
DISPLAY 0.617021 (-3650 1250);
PAINT SKYBLUE (-3650 1250);
FORCEPROP 1 LAST PACK_TYPE 0402V
J 0
(-3650 1100);
DISPLAY 0.617021 (-3650 1100);
PAINT SKYBLUE (-3650 1100);
FORCEPROP 1 LAST VOLTAGE 16V
J 0
(-3650 1300);
DISPLAY 0.617021 (-3650 1300);
PAINT SKYBLUE (-3650 1300);
FORCEPROP 1 LAST MATERIAL X7R
J 0
(-3650 1200);
DISPLAY 0.617021 (-3650 1200);
PAINT SKYBLUE (-3650 1200);
FORCEPROP 1 LASTPIN (-3700 1400) $PN 1
J 0
(-3690 1380);
DISPLAY 0.617021 (-3690 1380);
PAINT ORANGE (-3690 1380);
FORCEPROP 1 LASTPIN (-3700 1200) $PN 2
J 0
(-3690 1180);
DISPLAY 0.617021 (-3690 1180);
PAINT ORANGE (-3690 1180);
FORCEPROP 2 LAST ROOM CPLD
J 0
(-3650 1450);
DISPLAY 1.361702 (-3650 1450);
PAINT ORANGE (-3650 1450);
DISPLAY INVISIBLE (-3650 1450);
FORCEPROP 2 LAST $SEC 1
J 0
(-3650 1500);
DISPLAY 0.914894 (-3650 1500);
PAINT MONO (-3650 1500);
DISPLAY INVISIBLE (-3650 1500);
FORCEPROP 2 LAST CDS_SEC 1
J 0
(-3650 1500);
DISPLAY 1.361702 (-3650 1500);
PAINT ORANGE (-3650 1500);
DISPLAY INVISIBLE (-3650 1500);
FORCEPROP 2 LAST BOM_COST CPLD
J 0
(-3650 1500);
DISPLAY 1.361702 (-3650 1500);
PAINT ORANGE (-3650 1500);
DISPLAY INVISIBLE (-3650 1500);
FORCEPROP 2 LAST SIGNAL_MODEL DEFAULT_CAPACITOR_100000pF_2_1
J 0
(-3650 1500);
PAINT MONO (-3650 1500);
DISPLAY INVISIBLE (-3650 1500);
FORCEPROP 1 LAST PATH I11
J 0
(-3650 1450);
DISPLAY 0.978723 (-3650 1450);
PAINT WHITE (-3650 1450);
DISPLAY INVISIBLE (-3650 1450);
FORCEPROP 2 LAST CDS_LOCATION C3P51
J 0
(-3650 1400);
DISPLAY 0.617021 (-3650 1400);
PAINT AQUA (-3650 1400);
DISPLAY INVISIBLE (-3650 1400);
FORCEPROP 2 LAST CDS_LIB dev_discrete
J 0
(-3700 1300);
PAINT ORANGE (-3700 1300);
DISPLAY INVISIBLE (-3700 1300);
FORCEADD CAP_A..1
(-4200 1300);
FORCEPROP 1 LAST LOCATION C3P47
J 0
(-4150 1400);
DISPLAY 0.617021 (-4150 1400);
PAINT AQUA (-4150 1400);
FORCEPROP 1 LAST PART_NUMBER A36096-030
J 0
(-4150 1150);
DISPLAY 0.617021 (-4150 1150);
PAINT BLUE (-4150 1150);
FORCEPROP 1 LAST VALUE 0.1UF
J 0
(-4150 1350);
DISPLAY 0.617021 (-4150 1350);
PAINT SKYBLUE (-4150 1350);
FORCEPROP 1 LAST TOLERANCE 10%
J 0
(-4150 1250);
DISPLAY 0.617021 (-4150 1250);
PAINT SKYBLUE (-4150 1250);
FORCEPROP 1 LAST VOLTAGE 16V
J 0
(-4150 1300);
DISPLAY 0.617021 (-4150 1300);
PAINT SKYBLUE (-4150 1300);
FORCEPROP 1 LAST MATERIAL X7R
J 0
(-4150 1200);
DISPLAY 0.617021 (-4150 1200);
PAINT SKYBLUE (-4150 1200);
FORCEPROP 1 LASTPIN (-4200 1400) $PN 1
J 0
(-4190 1380);
DISPLAY 0.617021 (-4190 1380);
PAINT ORANGE (-4190 1380);
FORCEPROP 1 LASTPIN (-4200 1200) $PN 2
J 0
(-4190 1180);
DISPLAY 0.617021 (-4190 1180);
PAINT ORANGE (-4190 1180);
FORCEPROP 1 LAST PACK_TYPE 0402V
J 0
(-4150 1100);
DISPLAY 0.617021 (-4150 1100);
PAINT SKYBLUE (-4150 1100);
FORCEPROP 2 LAST ROOM CPLD
J 0
(-4150 1450);
DISPLAY 1.361702 (-4150 1450);
PAINT ORANGE (-4150 1450);
DISPLAY INVISIBLE (-4150 1450);
FORCEPROP 2 LAST $SEC 1
J 0
(-4150 1500);
DISPLAY 0.914894 (-4150 1500);
PAINT MONO (-4150 1500);
DISPLAY INVISIBLE (-4150 1500);
FORCEPROP 2 LAST CDS_SEC 1
J 0
(-4150 1500);
DISPLAY 1.361702 (-4150 1500);
PAINT ORANGE (-4150 1500);
DISPLAY INVISIBLE (-4150 1500);
FORCEPROP 2 LAST BOM_COST CPLD
J 0
(-4150 1500);
DISPLAY 1.361702 (-4150 1500);
PAINT ORANGE (-4150 1500);
DISPLAY INVISIBLE (-4150 1500);
FORCEPROP 2 LAST SIGNAL_MODEL DEFAULT_CAPACITOR_100000pF_2_1
J 0
(-4150 1500);
PAINT MONO (-4150 1500);
DISPLAY INVISIBLE (-4150 1500);
FORCEPROP 1 LAST PATH I12
J 0
(-4150 1450);
DISPLAY 0.978723 (-4150 1450);
PAINT WHITE (-4150 1450);
DISPLAY INVISIBLE (-4150 1450);
FORCEPROP 2 LAST CDS_LOCATION C3P47
J 0
(-4150 1400);
DISPLAY 0.617021 (-4150 1400);
PAINT AQUA (-4150 1400);
DISPLAY INVISIBLE (-4150 1400);
FORCEPROP 2 LAST CDS_LIB dev_discrete
J 0
(-4200 1300);
PAINT ORANGE (-4200 1300);
DISPLAY INVISIBLE (-4200 1300);
FORCEADD LCMXO2_A..6
(-1850 3900);
FORCEPROP 1 LAST LOCATION U8D7
J 0
(-2274 4726);
DISPLAY 0.617021 (-2274 4726);
PAINT AQUA (-2274 4726);
FORCEPROP 1 LAST MATERIAL IC
J 0
(-2275 4675);
DISPLAY 0.617021 (-2275 4675);
PAINT SKYBLUE (-2275 4675);
FORCEPROP 2 LASTPIN (-2300 3900) $PN M4
J 2
(-2310 3910);
DISPLAY 0.617021 (-2310 3910);
PAINT ORANGE (-2310 3910);
FORCEPROP 2 LASTPIN (-2300 3450) $PN D5
J 2
(-2310 3460);
DISPLAY 0.617021 (-2310 3460);
PAINT ORANGE (-2310 3460);
FORCEPROP 2 LASTPIN (-2300 4050) $PN E4
J 2
(-2310 4060);
DISPLAY 0.617021 (-2310 4060);
PAINT ORANGE (-2310 4060);
FORCEPROP 2 LASTPIN (-2300 4000) $PN H7
J 2
(-2310 4010);
DISPLAY 0.617021 (-2310 4010);
PAINT ORANGE (-2310 4010);
FORCEPROP 2 LASTPIN (-2300 3950) $PN J7
J 2
(-2310 3960);
DISPLAY 0.617021 (-2310 3960);
PAINT ORANGE (-2310 3960);
FORCEPROP 2 LASTPIN (-2300 3850) $PN N5
J 2
(-2310 3860);
DISPLAY 0.617021 (-2310 3860);
PAINT ORANGE (-2310 3860);
FORCEPROP 2 LASTPIN (-2300 3800) $PN K8
J 2
(-2310 3810);
DISPLAY 0.617021 (-2310 3810);
PAINT ORANGE (-2310 3810);
FORCEPROP 2 LASTPIN (-2300 3750) $PN N12
J 2
(-2310 3760);
DISPLAY 0.617021 (-2310 3760);
PAINT ORANGE (-2310 3760);
FORCEPROP 2 LASTPIN (-2300 3700) $PN K9
J 2
(-2310 3710);
DISPLAY 0.617021 (-2310 3710);
PAINT ORANGE (-2310 3710);
FORCEPROP 2 LASTPIN (-2300 3650) $PN M13
J 2
(-2310 3660);
DISPLAY 0.617021 (-2310 3660);
PAINT ORANGE (-2310 3660);
FORCEPROP 2 LASTPIN (-2300 3550) $PN H10
J 2
(-2310 3560);
DISPLAY 0.617021 (-2310 3560);
PAINT ORANGE (-2310 3560);
FORCEPROP 2 LASTPIN (-2300 3500) $PN E13
J 2
(-2310 3510);
DISPLAY 0.617021 (-2310 3510);
PAINT ORANGE (-2310 3510);
FORCEPROP 2 LASTPIN (-2300 3400) $PN G9
J 2
(-2310 3410);
DISPLAY 0.617021 (-2310 3410);
PAINT ORANGE (-2310 3410);
FORCEPROP 2 LASTPIN (-2300 3350) $PN D12
J 2
(-2310 3360);
DISPLAY 0.617021 (-2310 3360);
PAINT ORANGE (-2310 3360);
FORCEPROP 2 LASTPIN (-2300 3300) $PN G8
J 2
(-2310 3310);
DISPLAY 0.617021 (-2310 3310);
PAINT ORANGE (-2310 3310);
FORCEPROP 2 LASTPIN (-2300 4450) $PN K7
J 2
(-2310 4460);
DISPLAY 0.617021 (-2310 4460);
PAINT ORANGE (-2310 4460);
FORCEPROP 2 LASTPIN (-2300 4400) $PN G10
J 2
(-2310 4410);
DISPLAY 0.617021 (-2310 4410);
PAINT ORANGE (-2310 4410);
FORCEPROP 2 LASTPIN (-2300 4350) $PN G7
J 2
(-2310 4360);
DISPLAY 0.617021 (-2310 4360);
PAINT ORANGE (-2310 4360);
FORCEPROP 2 LASTPIN (-1400 4350) $PN R2
J 0
(-1390 4360);
DISPLAY 0.617021 (-1390 4360);
PAINT ORANGE (-1390 4360);
FORCEPROP 2 LASTPIN (-1400 4300) $PN P14
J 0
(-1390 4310);
DISPLAY 0.617021 (-1390 4310);
PAINT ORANGE (-1390 4310);
FORCEPROP 2 LASTPIN (-1400 4250) $PN P3
J 0
(-1390 4260);
DISPLAY 0.617021 (-1390 4260);
PAINT ORANGE (-1390 4260);
FORCEPROP 2 LASTPIN (-1400 4200) $PN N13
J 0
(-1390 4210);
DISPLAY 0.617021 (-1390 4210);
PAINT ORANGE (-1390 4210);
FORCEPROP 2 LASTPIN (-1400 4150) $PN N4
J 0
(-1390 4160);
DISPLAY 0.617021 (-1390 4160);
PAINT ORANGE (-1390 4160);
FORCEPROP 2 LASTPIN (-1400 4100) $PN M12
J 0
(-1390 4110);
DISPLAY 0.617021 (-1390 4110);
PAINT ORANGE (-1390 4110);
FORCEPROP 2 LASTPIN (-1400 4050) $PN M5
J 0
(-1390 4060);
DISPLAY 0.617021 (-1390 4060);
PAINT ORANGE (-1390 4060);
FORCEPROP 2 LASTPIN (-1400 4000) $PN L11
J 0
(-1390 4010);
DISPLAY 0.617021 (-1390 4010);
PAINT ORANGE (-1390 4010);
FORCEPROP 2 LASTPIN (-1400 3900) $PN J9
J 0
(-1390 3910);
DISPLAY 0.617021 (-1390 3910);
PAINT ORANGE (-1390 3910);
FORCEPROP 2 LASTPIN (-1400 3850) $PN J8
J 0
(-1390 3860);
DISPLAY 0.617021 (-1390 3860);
PAINT ORANGE (-1390 3860);
FORCEPROP 2 LASTPIN (-1400 3800) $PN H9
J 0
(-1390 3810);
DISPLAY 0.617021 (-1390 3810);
PAINT ORANGE (-1390 3810);
FORCEPROP 2 LASTPIN (-1400 3750) $PN H8
J 0
(-1390 3760);
DISPLAY 0.617021 (-1390 3760);
PAINT ORANGE (-1390 3760);
FORCEPROP 2 LASTPIN (-1400 3700) $PN F11
J 0
(-1390 3710);
DISPLAY 0.617021 (-1390 3710);
PAINT ORANGE (-1390 3710);
FORCEPROP 2 LASTPIN (-1400 3650) $PN F6
J 0
(-1390 3660);
DISPLAY 0.617021 (-1390 3660);
PAINT ORANGE (-1390 3660);
FORCEPROP 2 LASTPIN (-1400 3600) $PN E12
J 0
(-1390 3610);
DISPLAY 0.617021 (-1390 3610);
PAINT ORANGE (-1390 3610);
FORCEPROP 2 LASTPIN (-1400 3550) $PN E5
J 0
(-1390 3560);
DISPLAY 0.617021 (-1390 3560);
PAINT ORANGE (-1390 3560);
FORCEPROP 2 LASTPIN (-1400 3500) $PN D13
J 0
(-1390 3510);
DISPLAY 0.617021 (-1390 3510);
PAINT ORANGE (-1390 3510);
FORCEPROP 2 LASTPIN (-1400 3450) $PN D4
J 0
(-1390 3460);
DISPLAY 0.617021 (-1390 3460);
PAINT ORANGE (-1390 3460);
FORCEPROP 2 LASTPIN (-1400 3400) $PN C14
J 0
(-1390 3410);
DISPLAY 0.617021 (-1390 3410);
PAINT ORANGE (-1390 3410);
FORCEPROP 2 LASTPIN (-1400 3350) $PN C3
J 0
(-1390 3360);
DISPLAY 0.617021 (-1390 3360);
PAINT ORANGE (-1390 3360);
FORCEPROP 2 LASTPIN (-1400 3300) $PN B15
J 0
(-1390 3310);
DISPLAY 0.617021 (-1390 3310);
PAINT ORANGE (-1390 3310);
FORCEPROP 2 LASTPIN (-1400 3950) $PN L6
J 0
(-1390 3960);
DISPLAY 0.617021 (-1390 3960);
PAINT ORANGE (-1390 3960);
FORCEPROP 2 LASTPIN (-2300 4150) $PN A1
J 2
(-2310 4160);
DISPLAY 0.617021 (-2310 4160);
PAINT ORANGE (-2310 4160);
FORCEPROP 2 LASTPIN (-2300 4200) $PN A16
J 2
(-2310 4210);
DISPLAY 0.617021 (-2310 4210);
PAINT ORANGE (-2310 4210);
FORCEPROP 2 LASTPIN (-2300 4250) $PN T1
J 2
(-2310 4260);
DISPLAY 0.617021 (-2310 4260);
PAINT ORANGE (-2310 4260);
FORCEPROP 2 LASTPIN (-2300 4300) $PN T16
J 2
(-2310 4310);
DISPLAY 0.617021 (-2310 4310);
PAINT ORANGE (-2310 4310);
FORCEPROP 2 LASTPIN (-1400 3250) $PN B2
J 0
(-1390 3260);
DISPLAY 0.617021 (-1390 3260);
PAINT ORANGE (-1390 3260);
FORCEPROP 1 LAST PART_NUMBER H63395-001
J 0
(-2250 3100);
DISPLAY 0.617021 (-2250 3100);
PAINT BLUE (-2250 3100);
FORCEPROP 2 LASTPIN (-1400 4400) $PN R15
J 0
(-1390 4410);
DISPLAY 0.617021 (-1390 4410);
PAINT ORANGE (-1390 4410);
FORCEPROP 2 LASTPIN (-1400 4550) $PN A2
J 0
(-1390 4560);
DISPLAY 0.617021 (-1390 4560);
PAINT ORANGE (-1390 4560);
FORCEPROP 2 LASTPIN (-2300 3600) $PN J10
J 2
(-2310 3610);
DISPLAY 0.617021 (-2310 3610);
PAINT ORANGE (-2310 3610);
FORCEPROP 2 LASTPIN (-2300 4500) $PN K10
J 2
(-2310 4510);
DISPLAY 0.617021 (-2310 4510);
PAINT ORANGE (-2310 4510);
FORCEPROP 1 LAST PACK_TYPE 256BGA
J 0
(-2275 4776);
PAINT SKYBLUE (-2275 4776);
DISPLAY INVISIBLE (-2275 4776);
FORCEPROP 2 LAST ROOM CPLD
J 0
(-2250 4775);
DISPLAY 1.361702 (-2250 4775);
PAINT ORANGE (-2250 4775);
DISPLAY INVISIBLE (-2250 4775);
FORCEPROP 2 LAST SEC_TYPE 256BGA
J 0
(-2250 4775);
DISPLAY 1.021277 (-2250 4775);
PAINT ORANGE (-2250 4775);
DISPLAY INVISIBLE (-2250 4775);
FORCEPROP 2 LAST SEC 3
J 0
(-2250 4775);
DISPLAY 0.680851 (-2250 4775);
PAINT MONO (-2250 4775);
DISPLAY INVISIBLE (-2250 4775);
FORCEPROP 2 LAST CDS_LIB mstr_memory
J 0
(-1850 3900);
PAINT ORANGE (-1850 3900);
DISPLAY INVISIBLE (-1850 3900);
FORCEPROP 1 LAST CDS_LMAN_SYM_OUTLINE -400,750,400,-750
J 0
(-1850 3900);
DISPLAY 0.468085 (-1850 3900);
PAINT GREEN (-1850 3900);
DISPLAY INVISIBLE (-1850 3900);
FORCEPROP 1 LAST PATH I14
J 0
(-1624 4676);
PAINT GREEN (-1624 4676);
DISPLAY INVISIBLE (-1624 4676);
FORCEPROP 2 LAST BOM_COST CPLD
J 0
(-2250 4825);
DISPLAY 1.361702 (-2250 4825);
PAINT ORANGE (-2250 4825);
DISPLAY INVISIBLE (-2250 4825);
FORCEPROP 2 LAST CDS_LOCATION U8D7
J 0
(-2274 4726);
DISPLAY 0.617021 (-2274 4726);
PAINT AQUA (-2274 4726);
DISPLAY INVISIBLE (-2274 4726);
FORCEADD CAP_A..1
(-4550 1975);
FORCEPROP 1 LAST LOCATION C2R5
J 0
(-4500 2075);
DISPLAY 0.617021 (-4500 2075);
PAINT AQUA (-4500 2075);
FORCEPROP 1 LAST PART_NUMBER A36096-030
J 0
(-4500 1825);
DISPLAY 0.617021 (-4500 1825);
PAINT BLUE (-4500 1825);
FORCEPROP 1 LAST VALUE 0.1UF
J 0
(-4500 2025);
DISPLAY 0.617021 (-4500 2025);
PAINT SKYBLUE (-4500 2025);
FORCEPROP 1 LAST TOLERANCE 10%
J 0
(-4500 1925);
DISPLAY 0.617021 (-4500 1925);
PAINT SKYBLUE (-4500 1925);
FORCEPROP 1 LAST PACK_TYPE 0402V
J 0
(-4500 1775);
DISPLAY 0.617021 (-4500 1775);
PAINT SKYBLUE (-4500 1775);
FORCEPROP 1 LAST VOLTAGE 16V
J 0
(-4500 1975);
DISPLAY 0.617021 (-4500 1975);
PAINT SKYBLUE (-4500 1975);
FORCEPROP 1 LAST MATERIAL X7R
J 0
(-4500 1875);
DISPLAY 0.617021 (-4500 1875);
PAINT SKYBLUE (-4500 1875);
FORCEPROP 1 LASTPIN (-4550 2075) $PN 1
J 0
(-4540 2055);
DISPLAY 0.617021 (-4540 2055);
PAINT ORANGE (-4540 2055);
FORCEPROP 1 LASTPIN (-4550 1875) $PN 2
J 0
(-4540 1855);
DISPLAY 0.617021 (-4540 1855);
PAINT ORANGE (-4540 1855);
FORCEPROP 2 LAST ROOM CPLD
J 0
(-4500 2125);
DISPLAY 1.361702 (-4500 2125);
PAINT ORANGE (-4500 2125);
DISPLAY INVISIBLE (-4500 2125);
FORCEPROP 2 LAST SIGNAL_MODEL DEFAULT_CAPACITOR_100000pF_2_1
J 0
(-4500 2175);
PAINT MONO (-4500 2175);
DISPLAY INVISIBLE (-4500 2175);
FORCEPROP 2 LAST BOM_COST CPLD
J 0
(-4500 2175);
DISPLAY 1.361702 (-4500 2175);
PAINT ORANGE (-4500 2175);
DISPLAY INVISIBLE (-4500 2175);
FORCEPROP 2 LAST CDS_SEC 1
J 0
(-4500 2175);
PAINT MONO (-4500 2175);
DISPLAY INVISIBLE (-4500 2175);
FORCEPROP 2 LAST $SEC 1
J 0
(-4500 2175);
PAINT MONO (-4500 2175);
DISPLAY INVISIBLE (-4500 2175);
FORCEPROP 1 LAST PATH I15
J 0
(-4500 2125);
DISPLAY 0.978723 (-4500 2125);
PAINT WHITE (-4500 2125);
DISPLAY INVISIBLE (-4500 2125);
FORCEPROP 2 LAST CDS_LOCATION C2R5
J 0
(-4500 2075);
DISPLAY 0.617021 (-4500 2075);
PAINT AQUA (-4500 2075);
DISPLAY INVISIBLE (-4500 2075);
FORCEPROP 2 LAST CDS_LIB dev_discrete
J 0
(-4550 1975);
PAINT ORANGE (-4550 1975);
DISPLAY INVISIBLE (-4550 1975);
FORCEADD CAP_A..1
(-5025 1975);
FORCEPROP 1 LAST LOCATION C2P4
J 0
(-4975 2075);
DISPLAY 0.617021 (-4975 2075);
PAINT AQUA (-4975 2075);
FORCEPROP 1 LAST PART_NUMBER A36096-030
J 0
(-4975 1825);
DISPLAY 0.617021 (-4975 1825);
PAINT BLUE (-4975 1825);
FORCEPROP 1 LAST VALUE 0.1UF
J 0
(-4975 2025);
DISPLAY 0.617021 (-4975 2025);
PAINT SKYBLUE (-4975 2025);
FORCEPROP 1 LAST TOLERANCE 10%
J 0
(-4975 1925);
DISPLAY 0.617021 (-4975 1925);
PAINT SKYBLUE (-4975 1925);
FORCEPROP 1 LAST PACK_TYPE 0402V
J 0
(-4975 1775);
DISPLAY 0.617021 (-4975 1775);
PAINT SKYBLUE (-4975 1775);
FORCEPROP 1 LAST VOLTAGE 16V
J 0
(-4975 1975);
DISPLAY 0.617021 (-4975 1975);
PAINT SKYBLUE (-4975 1975);
FORCEPROP 1 LAST MATERIAL X7R
J 0
(-4975 1875);
DISPLAY 0.617021 (-4975 1875);
PAINT SKYBLUE (-4975 1875);
FORCEPROP 1 LASTPIN (-5025 2075) $PN 1
J 0
(-5015 2055);
DISPLAY 0.617021 (-5015 2055);
PAINT ORANGE (-5015 2055);
FORCEPROP 1 LASTPIN (-5025 1875) $PN 2
J 0
(-5015 1855);
DISPLAY 0.617021 (-5015 1855);
PAINT ORANGE (-5015 1855);
FORCEPROP 2 LAST ROOM CPLD
J 0
(-4975 2125);
DISPLAY 1.361702 (-4975 2125);
PAINT ORANGE (-4975 2125);
DISPLAY INVISIBLE (-4975 2125);
FORCEPROP 1 LAST PATH I16
J 0
(-4975 2125);
DISPLAY 0.978723 (-4975 2125);
PAINT WHITE (-4975 2125);
DISPLAY INVISIBLE (-4975 2125);
FORCEPROP 2 LAST CDS_LOCATION C2P4
J 0
(-4975 2075);
DISPLAY 0.617021 (-4975 2075);
PAINT AQUA (-4975 2075);
DISPLAY INVISIBLE (-4975 2075);
FORCEPROP 2 LAST SIGNAL_MODEL DEFAULT_CAPACITOR_100000pF_2_1
J 0
(-4975 2175);
PAINT MONO (-4975 2175);
DISPLAY INVISIBLE (-4975 2175);
FORCEPROP 2 LAST BOM_COST CPLD
J 0
(-4975 2175);
DISPLAY 1.361702 (-4975 2175);
PAINT ORANGE (-4975 2175);
DISPLAY INVISIBLE (-4975 2175);
FORCEPROP 2 LAST CDS_SEC 1
J 0
(-4975 2175);
PAINT MONO (-4975 2175);
DISPLAY INVISIBLE (-4975 2175);
FORCEPROP 2 LAST $SEC 1
J 0
(-4975 2175);
PAINT MONO (-4975 2175);
DISPLAY INVISIBLE (-4975 2175);
FORCEPROP 2 LAST CDS_LIB dev_discrete
J 0
(-5025 1975);
PAINT ORANGE (-5025 1975);
DISPLAY INVISIBLE (-5025 1975);
FORCEADD CAP_A..1
(-4725 1300);
FORCEPROP 1 LAST LOCATION C3P52
J 0
(-4675 1400);
DISPLAY 0.617021 (-4675 1400);
PAINT AQUA (-4675 1400);
FORCEPROP 1 LAST PART_NUMBER A36096-030
J 0
(-4675 1150);
DISPLAY 0.617021 (-4675 1150);
PAINT BLUE (-4675 1150);
FORCEPROP 1 LAST VALUE 0.1UF
J 0
(-4675 1350);
DISPLAY 0.617021 (-4675 1350);
PAINT SKYBLUE (-4675 1350);
FORCEPROP 1 LAST TOLERANCE 10%
J 0
(-4675 1250);
DISPLAY 0.617021 (-4675 1250);
PAINT SKYBLUE (-4675 1250);
FORCEPROP 1 LAST PACK_TYPE 0402V
J 0
(-4675 1100);
DISPLAY 0.617021 (-4675 1100);
PAINT SKYBLUE (-4675 1100);
FORCEPROP 1 LAST VOLTAGE 16V
J 0
(-4675 1300);
DISPLAY 0.617021 (-4675 1300);
PAINT SKYBLUE (-4675 1300);
FORCEPROP 1 LAST MATERIAL X7R
J 0
(-4675 1200);
DISPLAY 0.617021 (-4675 1200);
PAINT SKYBLUE (-4675 1200);
FORCEPROP 1 LASTPIN (-4725 1400) $PN 1
J 0
(-4715 1380);
DISPLAY 0.617021 (-4715 1380);
PAINT ORANGE (-4715 1380);
FORCEPROP 1 LASTPIN (-4725 1200) $PN 2
J 0
(-4715 1180);
DISPLAY 0.617021 (-4715 1180);
PAINT ORANGE (-4715 1180);
FORCEPROP 2 LAST ROOM CPLD
J 0
(-4675 1450);
DISPLAY 1.361702 (-4675 1450);
PAINT ORANGE (-4675 1450);
DISPLAY INVISIBLE (-4675 1450);
FORCEPROP 2 LAST CDS_SEC 1
J 0
(-4675 1500);
DISPLAY 1.361702 (-4675 1500);
PAINT ORANGE (-4675 1500);
DISPLAY INVISIBLE (-4675 1500);
FORCEPROP 2 LAST $SEC 1
J 0
(-4675 1500);
DISPLAY 0.914894 (-4675 1500);
PAINT MONO (-4675 1500);
DISPLAY INVISIBLE (-4675 1500);
FORCEPROP 2 LAST BOM_COST CPLD
J 0
(-4675 1500);
DISPLAY 1.361702 (-4675 1500);
PAINT ORANGE (-4675 1500);
DISPLAY INVISIBLE (-4675 1500);
FORCEPROP 2 LAST SIGNAL_MODEL DEFAULT_CAPACITOR_100000pF_2_1
J 0
(-4675 1500);
PAINT MONO (-4675 1500);
DISPLAY INVISIBLE (-4675 1500);
FORCEPROP 1 LAST PATH I17
J 0
(-4675 1450);
DISPLAY 0.978723 (-4675 1450);
PAINT WHITE (-4675 1450);
DISPLAY INVISIBLE (-4675 1450);
FORCEPROP 2 LAST CDS_LOCATION C3P52
J 0
(-4675 1400);
DISPLAY 0.617021 (-4675 1400);
PAINT AQUA (-4675 1400);
DISPLAY INVISIBLE (-4675 1400);
FORCEPROP 2 LAST CDS_LIB dev_discrete
J 0
(-4725 1300);
PAINT ORANGE (-4725 1300);
DISPLAY INVISIBLE (-4725 1300);
FORCEADD CAP_A..1
(-5225 1300);
FORCEPROP 1 LAST LOCATION C2P6
J 0
(-5175 1400);
DISPLAY 0.617021 (-5175 1400);
PAINT AQUA (-5175 1400);
FORCEPROP 1 LAST PART_NUMBER A36096-030
J 0
(-5175 1150);
DISPLAY 0.617021 (-5175 1150);
PAINT BLUE (-5175 1150);
FORCEPROP 1 LAST VALUE 0.1UF
J 0
(-5175 1350);
DISPLAY 0.617021 (-5175 1350);
PAINT SKYBLUE (-5175 1350);
FORCEPROP 1 LAST TOLERANCE 10%
J 0
(-5175 1250);
DISPLAY 0.617021 (-5175 1250);
PAINT SKYBLUE (-5175 1250);
FORCEPROP 1 LAST PACK_TYPE 0402V
J 0
(-5175 1100);
DISPLAY 0.617021 (-5175 1100);
PAINT SKYBLUE (-5175 1100);
FORCEPROP 1 LAST VOLTAGE 16V
J 0
(-5175 1300);
DISPLAY 0.617021 (-5175 1300);
PAINT SKYBLUE (-5175 1300);
FORCEPROP 1 LAST MATERIAL X7R
J 0
(-5175 1200);
DISPLAY 0.617021 (-5175 1200);
PAINT SKYBLUE (-5175 1200);
FORCEPROP 1 LASTPIN (-5225 1400) $PN 1
J 0
(-5215 1380);
DISPLAY 0.617021 (-5215 1380);
PAINT ORANGE (-5215 1380);
FORCEPROP 1 LASTPIN (-5225 1200) $PN 2
J 0
(-5215 1180);
DISPLAY 0.617021 (-5215 1180);
PAINT ORANGE (-5215 1180);
FORCEPROP 2 LAST ROOM CPLD
J 0
(-5175 1450);
DISPLAY 1.361702 (-5175 1450);
PAINT ORANGE (-5175 1450);
DISPLAY INVISIBLE (-5175 1450);
FORCEPROP 2 LAST $SEC 1
J 0
(-5175 1500);
DISPLAY 0.914894 (-5175 1500);
PAINT MONO (-5175 1500);
DISPLAY INVISIBLE (-5175 1500);
FORCEPROP 2 LAST CDS_SEC 1
J 0
(-5175 1500);
DISPLAY 1.361702 (-5175 1500);
PAINT ORANGE (-5175 1500);
DISPLAY INVISIBLE (-5175 1500);
FORCEPROP 2 LAST BOM_COST CPLD
J 0
(-5175 1500);
DISPLAY 1.361702 (-5175 1500);
PAINT ORANGE (-5175 1500);
DISPLAY INVISIBLE (-5175 1500);
FORCEPROP 2 LAST SIGNAL_MODEL DEFAULT_CAPACITOR_100000pF_2_1
J 0
(-5175 1500);
PAINT MONO (-5175 1500);
DISPLAY INVISIBLE (-5175 1500);
FORCEPROP 1 LAST PATH I18
J 0
(-5175 1450);
DISPLAY 0.978723 (-5175 1450);
PAINT WHITE (-5175 1450);
DISPLAY INVISIBLE (-5175 1450);
FORCEPROP 2 LAST CDS_LOCATION C2P6
J 0
(-5175 1400);
DISPLAY 0.617021 (-5175 1400);
PAINT AQUA (-5175 1400);
DISPLAY INVISIBLE (-5175 1400);
FORCEPROP 2 LAST CDS_LIB dev_discrete
J 0
(-5225 1300);
PAINT ORANGE (-5225 1300);
DISPLAY INVISIBLE (-5225 1300);
FORCEADD CAP_A..1
(-5500 1975);
FORCEPROP 1 LAST LOCATION C2R3
J 0
(-5450 2075);
DISPLAY 0.617021 (-5450 2075);
PAINT AQUA (-5450 2075);
FORCEPROP 1 LAST PART_NUMBER A36096-030
J 0
(-5450 1825);
DISPLAY 0.617021 (-5450 1825);
PAINT BLUE (-5450 1825);
FORCEPROP 1 LAST VALUE 0.1UF
J 0
(-5450 2025);
DISPLAY 0.617021 (-5450 2025);
PAINT SKYBLUE (-5450 2025);
FORCEPROP 1 LAST TOLERANCE 10%
J 0
(-5450 1925);
DISPLAY 0.617021 (-5450 1925);
PAINT SKYBLUE (-5450 1925);
FORCEPROP 1 LAST PACK_TYPE 0402V
J 0
(-5450 1775);
DISPLAY 0.617021 (-5450 1775);
PAINT SKYBLUE (-5450 1775);
FORCEPROP 1 LAST VOLTAGE 16V
J 0
(-5450 1975);
DISPLAY 0.617021 (-5450 1975);
PAINT SKYBLUE (-5450 1975);
FORCEPROP 1 LAST MATERIAL X7R
J 0
(-5450 1875);
DISPLAY 0.617021 (-5450 1875);
PAINT SKYBLUE (-5450 1875);
FORCEPROP 1 LASTPIN (-5500 2075) $PN 1
J 0
(-5490 2055);
DISPLAY 0.617021 (-5490 2055);
PAINT ORANGE (-5490 2055);
FORCEPROP 1 LASTPIN (-5500 1875) $PN 2
J 0
(-5490 1855);
DISPLAY 0.617021 (-5490 1855);
PAINT ORANGE (-5490 1855);
FORCEPROP 2 LAST ROOM CPLD
J 0
(-5450 2125);
DISPLAY 1.361702 (-5450 2125);
PAINT ORANGE (-5450 2125);
DISPLAY INVISIBLE (-5450 2125);
FORCEPROP 2 LAST $SEC 1
J 0
(-5450 2175);
PAINT MONO (-5450 2175);
DISPLAY INVISIBLE (-5450 2175);
FORCEPROP 2 LAST CDS_SEC 1
J 0
(-5450 2175);
PAINT MONO (-5450 2175);
DISPLAY INVISIBLE (-5450 2175);
FORCEPROP 2 LAST BOM_COST CPLD
J 0
(-5450 2175);
DISPLAY 1.361702 (-5450 2175);
PAINT ORANGE (-5450 2175);
DISPLAY INVISIBLE (-5450 2175);
FORCEPROP 2 LAST SIGNAL_MODEL DEFAULT_CAPACITOR_100000pF_2_1
J 0
(-5450 2175);
PAINT MONO (-5450 2175);
DISPLAY INVISIBLE (-5450 2175);
FORCEPROP 2 LAST CDS_LOCATION C2R3
J 0
(-5450 2075);
DISPLAY 0.617021 (-5450 2075);
PAINT AQUA (-5450 2075);
DISPLAY INVISIBLE (-5450 2075);
FORCEPROP 1 LAST PATH I19
J 0
(-5450 2125);
DISPLAY 0.978723 (-5450 2125);
PAINT WHITE (-5450 2125);
DISPLAY INVISIBLE (-5450 2125);
FORCEPROP 2 LAST CDS_LIB dev_discrete
J 0
(-5500 1975);
PAINT ORANGE (-5500 1975);
DISPLAY INVISIBLE (-5500 1975);
FORCEADD GND..1
(-1225 1625);
FORCEPROP 3 LASTPIN (-1225 1675) SIG_NAME GND\g
J 0
(-1215 1685);
DISPLAY 0.659574 (-1215 1685);
PAINT MONO (-1215 1685);
DISPLAY INVISIBLE (-1215 1685);
FORCEPROP 1 LAST VOLTAGE 0.0V
J 0
(-1270 1582);
DISPLAY 0.340426 (-1270 1582);
PAINT SKYBLUE (-1270 1582);
DISPLAY INVISIBLE (-1270 1582);
FORCEPROP 2 LAST ROOM CPLD
J 0
(-1450 1700);
DISPLAY 1.361702 (-1450 1700);
PAINT ORANGE (-1450 1700);
DISPLAY INVISIBLE (-1450 1700);
FORCEPROP 1 LAST SIZE 1B
J 0
(-1150 1575);
DISPLAY 1.170213 (-1150 1575);
PAINT AQUA (-1150 1575);
DISPLAY INVISIBLE (-1150 1575);
FORCEPROP 1 LAST PATH I2
J 0
(-1150 1625);
DISPLAY 0.872340 (-1150 1625);
PAINT AQUA (-1150 1625);
DISPLAY INVISIBLE (-1150 1625);
FORCEPROP 2 LAST CDS_LIB mstr_symbols
J 0
(-1225 1625);
PAINT ORANGE (-1225 1625);
DISPLAY INVISIBLE (-1225 1625);
FORCEPROP 2 LAST BOM_COST CPLD
J 0
(-1450 1750);
DISPLAY 1.361702 (-1450 1750);
PAINT ORANGE (-1450 1750);
DISPLAY INVISIBLE (-1450 1750);
FORCEPROP 1 LAST BODY_TYPE PLUMBING
J 0
(-1270 1582);
DISPLAY 0.340426 (-1270 1582);
PAINT GREEN (-1270 1582);
DISPLAY INVISIBLE (-1270 1582);
FORCEPROP 1 LAST HDL_POWER GND
J 0
(-1225 1775);
DISPLAY 1.170213 (-1225 1775);
PAINT GREEN (-1225 1775);
DISPLAY INVISIBLE (-1225 1775);
FORCEADD CAP_A..1
(-5975 1975);
FORCEPROP 1 LAST LOCATION C2P7
J 0
(-5925 2075);
DISPLAY 0.617021 (-5925 2075);
PAINT AQUA (-5925 2075);
FORCEPROP 1 LAST PART_NUMBER A36096-030
J 0
(-5925 1825);
DISPLAY 0.617021 (-5925 1825);
PAINT BLUE (-5925 1825);
FORCEPROP 1 LAST VALUE 0.1UF
J 0
(-5925 2025);
DISPLAY 0.617021 (-5925 2025);
PAINT SKYBLUE (-5925 2025);
FORCEPROP 1 LAST TOLERANCE 10%
J 0
(-5925 1925);
DISPLAY 0.617021 (-5925 1925);
PAINT SKYBLUE (-5925 1925);
FORCEPROP 1 LAST PACK_TYPE 0402V
J 0
(-5925 1775);
DISPLAY 0.617021 (-5925 1775);
PAINT SKYBLUE (-5925 1775);
FORCEPROP 1 LAST VOLTAGE 16V
J 0
(-5925 1975);
DISPLAY 0.617021 (-5925 1975);
PAINT SKYBLUE (-5925 1975);
FORCEPROP 1 LAST MATERIAL X7R
J 0
(-5925 1875);
DISPLAY 0.617021 (-5925 1875);
PAINT SKYBLUE (-5925 1875);
FORCEPROP 1 LASTPIN (-5975 2075) $PN 1
J 0
(-5965 2055);
DISPLAY 0.617021 (-5965 2055);
PAINT ORANGE (-5965 2055);
FORCEPROP 1 LASTPIN (-5975 1875) $PN 2
J 0
(-5965 1855);
DISPLAY 0.617021 (-5965 1855);
PAINT ORANGE (-5965 1855);
FORCEPROP 2 LAST ROOM CPLD
J 0
(-5925 2125);
DISPLAY 1.361702 (-5925 2125);
PAINT ORANGE (-5925 2125);
DISPLAY INVISIBLE (-5925 2125);
FORCEPROP 2 LAST $SEC 1
J 0
(-5925 2175);
PAINT MONO (-5925 2175);
DISPLAY INVISIBLE (-5925 2175);
FORCEPROP 2 LAST CDS_SEC 1
J 0
(-5925 2175);
PAINT MONO (-5925 2175);
DISPLAY INVISIBLE (-5925 2175);
FORCEPROP 2 LAST SIGNAL_MODEL DEFAULT_CAPACITOR_100000pF_2_1
J 0
(-5925 2175);
PAINT MONO (-5925 2175);
DISPLAY INVISIBLE (-5925 2175);
FORCEPROP 2 LAST BOM_COST CPLD
J 0
(-5925 2175);
DISPLAY 1.361702 (-5925 2175);
PAINT ORANGE (-5925 2175);
DISPLAY INVISIBLE (-5925 2175);
FORCEPROP 2 LAST CDS_LOCATION C2P7
J 0
(-5925 2075);
DISPLAY 0.617021 (-5925 2075);
PAINT AQUA (-5925 2075);
DISPLAY INVISIBLE (-5925 2075);
FORCEPROP 1 LAST PATH I20
J 0
(-5925 2125);
DISPLAY 0.978723 (-5925 2125);
PAINT WHITE (-5925 2125);
DISPLAY INVISIBLE (-5925 2125);
FORCEPROP 2 LAST CDS_LIB dev_discrete
J 0
(-5975 1975);
PAINT ORANGE (-5975 1975);
DISPLAY INVISIBLE (-5975 1975);
FORCEADD CAP_A..1
(-5700 1300);
FORCEPROP 1 LAST LOCATION C2R4
J 0
(-5650 1400);
DISPLAY 0.617021 (-5650 1400);
PAINT AQUA (-5650 1400);
FORCEPROP 1 LAST PART_NUMBER A36096-030
J 0
(-5650 1150);
DISPLAY 0.617021 (-5650 1150);
PAINT BLUE (-5650 1150);
FORCEPROP 1 LAST VALUE 0.1UF
J 0
(-5650 1350);
DISPLAY 0.617021 (-5650 1350);
PAINT SKYBLUE (-5650 1350);
FORCEPROP 1 LAST TOLERANCE 10%
J 0
(-5650 1250);
DISPLAY 0.617021 (-5650 1250);
PAINT SKYBLUE (-5650 1250);
FORCEPROP 1 LAST PACK_TYPE 0402V
J 0
(-5650 1100);
DISPLAY 0.617021 (-5650 1100);
PAINT SKYBLUE (-5650 1100);
FORCEPROP 1 LAST VOLTAGE 16V
J 0
(-5650 1300);
DISPLAY 0.617021 (-5650 1300);
PAINT SKYBLUE (-5650 1300);
FORCEPROP 1 LAST MATERIAL X7R
J 0
(-5650 1200);
DISPLAY 0.617021 (-5650 1200);
PAINT SKYBLUE (-5650 1200);
FORCEPROP 1 LASTPIN (-5700 1400) $PN 1
J 0
(-5690 1380);
DISPLAY 0.617021 (-5690 1380);
PAINT ORANGE (-5690 1380);
FORCEPROP 1 LASTPIN (-5700 1200) $PN 2
J 0
(-5690 1180);
DISPLAY 0.617021 (-5690 1180);
PAINT ORANGE (-5690 1180);
FORCEPROP 2 LAST ROOM CPLD
J 0
(-5650 1450);
DISPLAY 1.361702 (-5650 1450);
PAINT ORANGE (-5650 1450);
DISPLAY INVISIBLE (-5650 1450);
FORCEPROP 2 LAST CDS_SEC 1
J 0
(-5650 1500);
DISPLAY 1.361702 (-5650 1500);
PAINT ORANGE (-5650 1500);
DISPLAY INVISIBLE (-5650 1500);
FORCEPROP 2 LAST $SEC 1
J 0
(-5650 1500);
DISPLAY 0.914894 (-5650 1500);
PAINT MONO (-5650 1500);
DISPLAY INVISIBLE (-5650 1500);
FORCEPROP 2 LAST BOM_COST CPLD
J 0
(-5650 1500);
DISPLAY 1.361702 (-5650 1500);
PAINT ORANGE (-5650 1500);
DISPLAY INVISIBLE (-5650 1500);
FORCEPROP 2 LAST SIGNAL_MODEL DEFAULT_CAPACITOR_100000pF_2_1
J 0
(-5650 1500);
PAINT MONO (-5650 1500);
DISPLAY INVISIBLE (-5650 1500);
FORCEPROP 1 LAST PATH I21
J 0
(-5650 1450);
DISPLAY 0.978723 (-5650 1450);
PAINT WHITE (-5650 1450);
DISPLAY INVISIBLE (-5650 1450);
FORCEPROP 2 LAST CDS_LOCATION C2R4
J 0
(-5650 1400);
DISPLAY 0.617021 (-5650 1400);
PAINT AQUA (-5650 1400);
DISPLAY INVISIBLE (-5650 1400);
FORCEPROP 2 LAST CDS_LIB dev_discrete
J 0
(-5700 1300);
PAINT ORANGE (-5700 1300);
DISPLAY INVISIBLE (-5700 1300);
FORCEADD CAP_A..1
(-6250 1300);
FORCEPROP 1 LAST LOCATION C2P3
J 0
(-6200 1400);
DISPLAY 0.617021 (-6200 1400);
PAINT AQUA (-6200 1400);
FORCEPROP 1 LAST PART_NUMBER A36096-030
J 0
(-6200 1150);
DISPLAY 0.617021 (-6200 1150);
PAINT BLUE (-6200 1150);
FORCEPROP 1 LAST VALUE 0.1UF
J 0
(-6200 1350);
DISPLAY 0.617021 (-6200 1350);
PAINT SKYBLUE (-6200 1350);
FORCEPROP 1 LAST TOLERANCE 10%
J 0
(-6200 1250);
DISPLAY 0.617021 (-6200 1250);
PAINT SKYBLUE (-6200 1250);
FORCEPROP 1 LAST PACK_TYPE 0402V
J 0
(-6200 1100);
DISPLAY 0.617021 (-6200 1100);
PAINT SKYBLUE (-6200 1100);
FORCEPROP 1 LAST VOLTAGE 16V
J 0
(-6200 1300);
DISPLAY 0.617021 (-6200 1300);
PAINT SKYBLUE (-6200 1300);
FORCEPROP 1 LAST MATERIAL X7R
J 0
(-6200 1200);
DISPLAY 0.617021 (-6200 1200);
PAINT SKYBLUE (-6200 1200);
FORCEPROP 1 LASTPIN (-6250 1400) $PN 1
J 0
(-6240 1380);
DISPLAY 0.617021 (-6240 1380);
PAINT ORANGE (-6240 1380);
FORCEPROP 1 LASTPIN (-6250 1200) $PN 2
J 0
(-6240 1180);
DISPLAY 0.617021 (-6240 1180);
PAINT ORANGE (-6240 1180);
FORCEPROP 2 LAST ROOM CPLD
J 0
(-6200 1450);
DISPLAY 1.361702 (-6200 1450);
PAINT ORANGE (-6200 1450);
DISPLAY INVISIBLE (-6200 1450);
FORCEPROP 2 LAST $SEC 1
J 0
(-6200 1500);
DISPLAY 0.914894 (-6200 1500);
PAINT MONO (-6200 1500);
DISPLAY INVISIBLE (-6200 1500);
FORCEPROP 2 LAST CDS_SEC 1
J 0
(-6200 1500);
DISPLAY 1.361702 (-6200 1500);
PAINT ORANGE (-6200 1500);
DISPLAY INVISIBLE (-6200 1500);
FORCEPROP 2 LAST BOM_COST CPLD
J 0
(-6200 1500);
DISPLAY 1.361702 (-6200 1500);
PAINT ORANGE (-6200 1500);
DISPLAY INVISIBLE (-6200 1500);
FORCEPROP 2 LAST SIGNAL_MODEL DEFAULT_CAPACITOR_100000pF_2_1
J 0
(-6200 1500);
PAINT MONO (-6200 1500);
DISPLAY INVISIBLE (-6200 1500);
FORCEPROP 1 LAST PATH I22
J 0
(-6200 1450);
DISPLAY 0.978723 (-6200 1450);
PAINT WHITE (-6200 1450);
DISPLAY INVISIBLE (-6200 1450);
FORCEPROP 2 LAST CDS_LOCATION C2P3
J 0
(-6200 1400);
DISPLAY 0.617021 (-6200 1400);
PAINT AQUA (-6200 1400);
DISPLAY INVISIBLE (-6200 1400);
FORCEPROP 2 LAST CDS_LIB dev_discrete
J 0
(-6250 1300);
PAINT ORANGE (-6250 1300);
DISPLAY INVISIBLE (-6250 1300);
FORCEADD CAP_A..1
(-6450 1975);
FORCEPROP 1 LAST LOCATION C3P44
J 0
(-6400 2075);
DISPLAY 0.617021 (-6400 2075);
PAINT AQUA (-6400 2075);
FORCEPROP 1 LAST PART_NUMBER A36096-030
J 0
(-6400 1825);
DISPLAY 0.617021 (-6400 1825);
PAINT BLUE (-6400 1825);
FORCEPROP 1 LAST VALUE 0.1UF
J 0
(-6400 2025);
DISPLAY 0.617021 (-6400 2025);
PAINT SKYBLUE (-6400 2025);
FORCEPROP 1 LAST TOLERANCE 10%
J 0
(-6400 1925);
DISPLAY 0.617021 (-6400 1925);
PAINT SKYBLUE (-6400 1925);
FORCEPROP 1 LAST PACK_TYPE 0402V
J 0
(-6400 1775);
DISPLAY 0.617021 (-6400 1775);
PAINT SKYBLUE (-6400 1775);
FORCEPROP 1 LAST VOLTAGE 16V
J 0
(-6400 1975);
DISPLAY 0.617021 (-6400 1975);
PAINT SKYBLUE (-6400 1975);
FORCEPROP 1 LAST MATERIAL X7R
J 0
(-6400 1875);
DISPLAY 0.617021 (-6400 1875);
PAINT SKYBLUE (-6400 1875);
FORCEPROP 1 LASTPIN (-6450 1875) $PN 2
J 0
(-6440 1855);
DISPLAY 0.617021 (-6440 1855);
PAINT ORANGE (-6440 1855);
FORCEPROP 1 LASTPIN (-6450 2075) $PN 1
J 0
(-6440 2055);
DISPLAY 0.617021 (-6440 2055);
PAINT ORANGE (-6440 2055);
FORCEPROP 2 LAST ROOM CPLD
J 0
(-6400 2125);
DISPLAY 1.361702 (-6400 2125);
PAINT ORANGE (-6400 2125);
DISPLAY INVISIBLE (-6400 2125);
FORCEPROP 1 LAST PATH I23
J 0
(-6400 2125);
DISPLAY 0.978723 (-6400 2125);
PAINT WHITE (-6400 2125);
DISPLAY INVISIBLE (-6400 2125);
FORCEPROP 2 LAST CDS_LOCATION C3P44
J 0
(-6400 2075);
DISPLAY 0.617021 (-6400 2075);
PAINT AQUA (-6400 2075);
DISPLAY INVISIBLE (-6400 2075);
FORCEPROP 2 LAST BOM_COST CPLD
J 0
(-6400 2175);
DISPLAY 1.361702 (-6400 2175);
PAINT ORANGE (-6400 2175);
DISPLAY INVISIBLE (-6400 2175);
FORCEPROP 2 LAST SIGNAL_MODEL DEFAULT_CAPACITOR_100000pF_2_1
J 0
(-6400 2175);
PAINT MONO (-6400 2175);
DISPLAY INVISIBLE (-6400 2175);
FORCEPROP 2 LAST CDS_SEC 1
J 0
(-6400 2175);
PAINT MONO (-6400 2175);
DISPLAY INVISIBLE (-6400 2175);
FORCEPROP 2 LAST $SEC 1
J 0
(-6400 2175);
PAINT MONO (-6400 2175);
DISPLAY INVISIBLE (-6400 2175);
FORCEPROP 2 LAST CDS_LIB dev_discrete
J 0
(-6450 1975);
PAINT ORANGE (-6450 1975);
DISPLAY INVISIBLE (-6450 1975);
FORCEADD CAP_A..1
(-6925 1975);
FORCEPROP 1 LAST LOCATION C3P48
J 0
(-6875 2075);
DISPLAY 0.617021 (-6875 2075);
PAINT AQUA (-6875 2075);
FORCEPROP 1 LAST PART_NUMBER A36096-030
J 0
(-6875 1825);
DISPLAY 0.617021 (-6875 1825);
PAINT BLUE (-6875 1825);
FORCEPROP 1 LAST VALUE 0.1UF
J 0
(-6875 2025);
DISPLAY 0.617021 (-6875 2025);
PAINT SKYBLUE (-6875 2025);
FORCEPROP 1 LAST TOLERANCE 10%
J 0
(-6875 1925);
DISPLAY 0.617021 (-6875 1925);
PAINT SKYBLUE (-6875 1925);
FORCEPROP 1 LAST PACK_TYPE 0402V
J 0
(-6875 1775);
DISPLAY 0.617021 (-6875 1775);
PAINT SKYBLUE (-6875 1775);
FORCEPROP 1 LAST VOLTAGE 16V
J 0
(-6875 1975);
DISPLAY 0.617021 (-6875 1975);
PAINT SKYBLUE (-6875 1975);
FORCEPROP 1 LAST MATERIAL X7R
J 0
(-6875 1875);
DISPLAY 0.617021 (-6875 1875);
PAINT SKYBLUE (-6875 1875);
FORCEPROP 1 LASTPIN (-6925 2075) $PN 1
J 0
(-6915 2055);
DISPLAY 0.617021 (-6915 2055);
PAINT ORANGE (-6915 2055);
FORCEPROP 1 LASTPIN (-6925 1875) $PN 2
J 0
(-6915 1855);
DISPLAY 0.617021 (-6915 1855);
PAINT ORANGE (-6915 1855);
FORCEPROP 2 LAST ROOM CPLD
J 0
(-6875 2125);
DISPLAY 1.361702 (-6875 2125);
PAINT ORANGE (-6875 2125);
DISPLAY INVISIBLE (-6875 2125);
FORCEPROP 2 LAST SEC 1
J 0
(-6875 2175);
DISPLAY 0.914894 (-6875 2175);
PAINT MONO (-6875 2175);
DISPLAY INVISIBLE (-6875 2175);
FORCEPROP 2 LAST SEC_TYPE 0402V
J 0
(-6875 2175);
DISPLAY 1.361702 (-6875 2175);
PAINT ORANGE (-6875 2175);
DISPLAY INVISIBLE (-6875 2175);
FORCEPROP 2 LAST CDS_SEC 1
J 0
(-6875 2125);
PAINT ORANGE (-6875 2125);
DISPLAY INVISIBLE (-6875 2125);
FORCEPROP 2 LAST BOM_COST CPLD
J 0
(-6875 2175);
DISPLAY 1.361702 (-6875 2175);
PAINT ORANGE (-6875 2175);
DISPLAY INVISIBLE (-6875 2175);
FORCEPROP 2 LAST SIGNAL_MODEL DEFAULT_CAPACITOR_100000pF_2_1
J 0
(-6875 2175);
PAINT MONO (-6875 2175);
DISPLAY INVISIBLE (-6875 2175);
FORCEPROP 2 LAST CDS_LOCATION C3P48
J 0
(-6875 2075);
DISPLAY 0.617021 (-6875 2075);
PAINT AQUA (-6875 2075);
DISPLAY INVISIBLE (-6875 2075);
FORCEPROP 1 LAST PATH I25
J 0
(-6875 2125);
DISPLAY 0.978723 (-6875 2125);
PAINT WHITE (-6875 2125);
DISPLAY INVISIBLE (-6875 2125);
FORCEPROP 2 LAST CDS_LIB dev_discrete
J 0
(-6925 1975);
PAINT ORANGE (-6925 1975);
DISPLAY INVISIBLE (-6925 1975);
FORCEADD GND..1
(-6475 1000);
FORCEPROP 3 LASTPIN (-6475 1050) SIG_NAME GND\g
J 0
(-6465 1060);
DISPLAY 0.659574 (-6465 1060);
PAINT MONO (-6465 1060);
DISPLAY INVISIBLE (-6465 1060);
FORCEPROP 1 LAST VOLTAGE 0.0V
J 0
(-6520 957);
DISPLAY 0.340426 (-6520 957);
PAINT SKYBLUE (-6520 957);
DISPLAY INVISIBLE (-6520 957);
FORCEPROP 2 LAST ROOM CPLD
J 0
(-6700 1075);
DISPLAY 1.361702 (-6700 1075);
PAINT ORANGE (-6700 1075);
DISPLAY INVISIBLE (-6700 1075);
FORCEPROP 2 LAST BOM_COST CPLD
J 0
(-6700 1125);
DISPLAY 1.361702 (-6700 1125);
PAINT ORANGE (-6700 1125);
DISPLAY INVISIBLE (-6700 1125);
FORCEPROP 1 LAST PATH I26
J 0
(-6400 1000);
DISPLAY 0.872340 (-6400 1000);
PAINT AQUA (-6400 1000);
DISPLAY INVISIBLE (-6400 1000);
FORCEPROP 2 LAST CDS_LIB mstr_symbols
J 0
(-6475 1000);
PAINT ORANGE (-6475 1000);
DISPLAY INVISIBLE (-6475 1000);
FORCEPROP 1 LAST SIZE 1B
J 0
(-6400 950);
DISPLAY 1.170213 (-6400 950);
PAINT AQUA (-6400 950);
DISPLAY INVISIBLE (-6400 950);
FORCEPROP 1 LAST BODY_TYPE PLUMBING
J 0
(-6520 957);
DISPLAY 0.340426 (-6520 957);
PAINT GREEN (-6520 957);
DISPLAY INVISIBLE (-6520 957);
FORCEPROP 1 LAST HDL_POWER GND
J 0
(-6475 1150);
DISPLAY 1.170213 (-6475 1150);
PAINT GREEN (-6475 1150);
DISPLAY INVISIBLE (-6475 1150);
FORCEADD CAP_A..1
(-6850 1300);
FORCEPROP 1 LAST LOCATION C2R2
J 0
(-6800 1400);
DISPLAY 0.617021 (-6800 1400);
PAINT AQUA (-6800 1400);
FORCEPROP 1 LAST PART_NUMBER A36096-030
J 0
(-6800 1150);
DISPLAY 0.617021 (-6800 1150);
PAINT BLUE (-6800 1150);
FORCEPROP 1 LAST VALUE 0.1UF
J 0
(-6800 1350);
DISPLAY 0.617021 (-6800 1350);
PAINT SKYBLUE (-6800 1350);
FORCEPROP 1 LAST TOLERANCE 10%
J 0
(-6800 1250);
DISPLAY 0.617021 (-6800 1250);
PAINT SKYBLUE (-6800 1250);
FORCEPROP 1 LAST PACK_TYPE 0402V
J 0
(-6800 1100);
DISPLAY 0.617021 (-6800 1100);
PAINT SKYBLUE (-6800 1100);
FORCEPROP 1 LAST VOLTAGE 16V
J 0
(-6800 1300);
DISPLAY 0.617021 (-6800 1300);
PAINT SKYBLUE (-6800 1300);
FORCEPROP 1 LAST MATERIAL X7R
J 0
(-6800 1200);
DISPLAY 0.617021 (-6800 1200);
PAINT SKYBLUE (-6800 1200);
FORCEPROP 1 LASTPIN (-6850 1400) $PN 1
J 0
(-6840 1380);
DISPLAY 0.617021 (-6840 1380);
PAINT ORANGE (-6840 1380);
FORCEPROP 1 LASTPIN (-6850 1200) $PN 2
J 0
(-6840 1180);
DISPLAY 0.617021 (-6840 1180);
PAINT ORANGE (-6840 1180);
FORCEPROP 2 LAST ROOM CPLD
J 0
(-6800 1450);
DISPLAY 1.361702 (-6800 1450);
PAINT ORANGE (-6800 1450);
DISPLAY INVISIBLE (-6800 1450);
FORCEPROP 2 LAST $SEC 1
J 0
(-6800 1500);
DISPLAY 0.914894 (-6800 1500);
PAINT MONO (-6800 1500);
DISPLAY INVISIBLE (-6800 1500);
FORCEPROP 2 LAST CDS_SEC 1
J 0
(-6800 1500);
DISPLAY 1.361702 (-6800 1500);
PAINT ORANGE (-6800 1500);
DISPLAY INVISIBLE (-6800 1500);
FORCEPROP 2 LAST BOM_COST CPLD
J 0
(-6800 1500);
DISPLAY 1.361702 (-6800 1500);
PAINT ORANGE (-6800 1500);
DISPLAY INVISIBLE (-6800 1500);
FORCEPROP 2 LAST SIGNAL_MODEL DEFAULT_CAPACITOR_100000pF_2_1
J 0
(-6800 1500);
PAINT MONO (-6800 1500);
DISPLAY INVISIBLE (-6800 1500);
FORCEPROP 1 LAST PATH I28
J 0
(-6800 1450);
DISPLAY 0.978723 (-6800 1450);
PAINT WHITE (-6800 1450);
DISPLAY INVISIBLE (-6800 1450);
FORCEPROP 2 LAST CDS_LOCATION C2R2
J 0
(-6800 1400);
DISPLAY 0.617021 (-6800 1400);
PAINT AQUA (-6800 1400);
DISPLAY INVISIBLE (-6800 1400);
FORCEPROP 2 LAST CDS_LIB dev_discrete
J 0
(-6850 1300);
PAINT ORANGE (-6850 1300);
DISPLAY INVISIBLE (-6850 1300);
FORCEADD P3V3_STBY..1
(-2500 4700);
FORCEPROP 3 LASTPIN (-2500 4650) SIG_NAME P3V3_STBY\g
J 0
(-2490 4660);
DISPLAY 0.659574 (-2490 4660);
PAINT MONO (-2490 4660);
DISPLAY INVISIBLE (-2490 4660);
FORCEPROP 1 LAST VOLTAGE 3.3V
J 0
(-2545 4657);
DISPLAY 0.340426 (-2545 4657);
PAINT SKYBLUE (-2545 4657);
DISPLAY INVISIBLE (-2545 4657);
FORCEPROP 1 LAST SIZE 1B
J 0
(-2455 4722);
DISPLAY 0.340426 (-2455 4722);
PAINT GREEN (-2455 4722);
DISPLAY INVISIBLE (-2455 4722);
FORCEPROP 2 LAST CDS_LIB mstr_symbols
J 0
(-2500 4700);
PAINT ORANGE (-2500 4700);
DISPLAY INVISIBLE (-2500 4700);
FORCEPROP 1 LAST PATH I29
J 0
(-2455 4702);
DISPLAY 0.340426 (-2455 4702);
PAINT GREEN (-2455 4702);
DISPLAY INVISIBLE (-2455 4702);
FORCEPROP 1 LAST BODY_TYPE PLUMBING
J 0
(-2545 4657);
DISPLAY 0.340426 (-2545 4657);
PAINT GREEN (-2545 4657);
DISPLAY INVISIBLE (-2545 4657);
FORCEPROP 1 LAST HDL_POWER P3V3_STBY
J 0
(-2800 4575);
DISPLAY 0.872340 (-2800 4575);
PAINT ORANGE (-2800 4575);
DISPLAY INVISIBLE (-2800 4575);
FORCEADD CAP_A..1
(-1700 1975);
FORCEPROP 1 LAST LOCATION C2P5
J 0
(-1650 2075);
DISPLAY 0.617021 (-1650 2075);
PAINT AQUA (-1650 2075);
FORCEPROP 1 LAST PART_NUMBER A36096-030
J 0
(-1650 1825);
DISPLAY 0.617021 (-1650 1825);
PAINT BLUE (-1650 1825);
FORCEPROP 1 LAST VALUE 0.1UF
J 0
(-1650 2025);
DISPLAY 0.617021 (-1650 2025);
PAINT SKYBLUE (-1650 2025);
FORCEPROP 1 LAST TOLERANCE 10%
J 0
(-1650 1925);
DISPLAY 0.617021 (-1650 1925);
PAINT SKYBLUE (-1650 1925);
FORCEPROP 1 LAST PACK_TYPE 0402V
J 0
(-1650 1775);
DISPLAY 0.617021 (-1650 1775);
PAINT SKYBLUE (-1650 1775);
FORCEPROP 1 LAST VOLTAGE 16V
J 0
(-1650 1975);
DISPLAY 0.617021 (-1650 1975);
PAINT SKYBLUE (-1650 1975);
FORCEPROP 1 LAST MATERIAL X7R
J 0
(-1650 1875);
DISPLAY 0.617021 (-1650 1875);
PAINT SKYBLUE (-1650 1875);
FORCEPROP 1 LASTPIN (-1700 2075) $PN 1
J 0
(-1690 2055);
DISPLAY 0.617021 (-1690 2055);
PAINT ORANGE (-1690 2055);
FORCEPROP 1 LASTPIN (-1700 1875) $PN 2
J 0
(-1690 1855);
DISPLAY 0.617021 (-1690 1855);
PAINT ORANGE (-1690 1855);
FORCEPROP 2 LAST ROOM CPLD
J 0
(-1650 2125);
DISPLAY 1.361702 (-1650 2125);
PAINT ORANGE (-1650 2125);
DISPLAY INVISIBLE (-1650 2125);
FORCEPROP 1 LAST PATH I3
J 0
(-1650 2125);
DISPLAY 0.978723 (-1650 2125);
PAINT WHITE (-1650 2125);
DISPLAY INVISIBLE (-1650 2125);
FORCEPROP 2 LAST CDS_LOCATION C2P5
J 0
(-1650 2075);
DISPLAY 0.617021 (-1650 2075);
PAINT AQUA (-1650 2075);
DISPLAY INVISIBLE (-1650 2075);
FORCEPROP 2 LAST SIGNAL_MODEL DEFAULT_CAPACITOR_100000pF_2_1
J 0
(-1650 2175);
PAINT MONO (-1650 2175);
DISPLAY INVISIBLE (-1650 2175);
FORCEPROP 2 LAST BOM_COST CPLD
J 0
(-1650 2175);
DISPLAY 1.361702 (-1650 2175);
PAINT ORANGE (-1650 2175);
DISPLAY INVISIBLE (-1650 2175);
FORCEPROP 2 LAST CDS_SEC 1
J 0
(-1650 2175);
PAINT MONO (-1650 2175);
DISPLAY INVISIBLE (-1650 2175);
FORCEPROP 2 LAST $SEC 1
J 0
(-1650 2175);
PAINT MONO (-1650 2175);
DISPLAY INVISIBLE (-1650 2175);
FORCEPROP 2 LAST CDS_LIB dev_discrete
J 0
(-1700 1975);
PAINT ORANGE (-1700 1975);
DISPLAY INVISIBLE (-1700 1975);
FORCEADD P3V3_STBY..1
(-6925 2275);
FORCEPROP 3 LASTPIN (-6925 2225) SIG_NAME P3V3_STBY\g
J 0
(-6915 2235);
DISPLAY 0.659574 (-6915 2235);
PAINT MONO (-6915 2235);
DISPLAY INVISIBLE (-6915 2235);
FORCEPROP 1 LAST VOLTAGE 3.3V
J 0
(-6970 2232);
DISPLAY 0.340426 (-6970 2232);
PAINT SKYBLUE (-6970 2232);
DISPLAY INVISIBLE (-6970 2232);
FORCEPROP 1 LAST PATH I30
J 0
(-6880 2277);
DISPLAY 0.340426 (-6880 2277);
PAINT GREEN (-6880 2277);
DISPLAY INVISIBLE (-6880 2277);
FORCEPROP 1 LAST SIZE 1B
J 0
(-6880 2297);
DISPLAY 0.340426 (-6880 2297);
PAINT GREEN (-6880 2297);
DISPLAY INVISIBLE (-6880 2297);
FORCEPROP 2 LAST CDS_LIB mstr_symbols
J 0
(-6925 2275);
PAINT ORANGE (-6925 2275);
DISPLAY INVISIBLE (-6925 2275);
FORCEPROP 1 LAST BODY_TYPE PLUMBING
J 0
(-6970 2232);
DISPLAY 0.340426 (-6970 2232);
PAINT GREEN (-6970 2232);
DISPLAY INVISIBLE (-6970 2232);
FORCEPROP 1 LAST HDL_POWER P3V3_STBY
J 0
(-7225 2150);
DISPLAY 0.872340 (-7225 2150);
PAINT ORANGE (-7225 2150);
DISPLAY INVISIBLE (-7225 2150);
FORCEADD P3V3_STBY..1
(-6850 1525);
FORCEPROP 3 LASTPIN (-6850 1475) SIG_NAME P3V3_STBY\g
J 0
(-6840 1485);
DISPLAY 0.659574 (-6840 1485);
PAINT MONO (-6840 1485);
DISPLAY INVISIBLE (-6840 1485);
FORCEPROP 1 LAST VOLTAGE 3.3V
J 0
(-6895 1482);
DISPLAY 0.340426 (-6895 1482);
PAINT SKYBLUE (-6895 1482);
DISPLAY INVISIBLE (-6895 1482);
FORCEPROP 1 LAST SIZE 1B
J 0
(-6805 1547);
DISPLAY 0.340426 (-6805 1547);
PAINT GREEN (-6805 1547);
DISPLAY INVISIBLE (-6805 1547);
FORCEPROP 1 LAST PATH I31
J 0
(-6805 1527);
DISPLAY 0.340426 (-6805 1527);
PAINT GREEN (-6805 1527);
DISPLAY INVISIBLE (-6805 1527);
FORCEPROP 2 LAST CDS_LIB mstr_symbols
J 0
(-6850 1525);
PAINT ORANGE (-6850 1525);
DISPLAY INVISIBLE (-6850 1525);
FORCEPROP 1 LAST BODY_TYPE PLUMBING
J 0
(-6895 1482);
DISPLAY 0.340426 (-6895 1482);
PAINT GREEN (-6895 1482);
DISPLAY INVISIBLE (-6895 1482);
FORCEPROP 1 LAST HDL_POWER P3V3_STBY
J 0
(-7150 1400);
DISPLAY 0.872340 (-7150 1400);
PAINT ORANGE (-7150 1400);
DISPLAY INVISIBLE (-7150 1400);
FORCEADD P3V3_STBY..1
(-6150 4600);
FORCEPROP 3 LASTPIN (-6150 4550) SIG_NAME P3V3_STBY\g
J 0
(-6140 4560);
DISPLAY 0.659574 (-6140 4560);
PAINT MONO (-6140 4560);
DISPLAY INVISIBLE (-6140 4560);
FORCEPROP 1 LAST VOLTAGE 3.3V
J 0
(-6195 4557);
DISPLAY 0.340426 (-6195 4557);
PAINT SKYBLUE (-6195 4557);
DISPLAY INVISIBLE (-6195 4557);
FORCEPROP 1 LAST SIZE 1B
J 0
(-6105 4622);
DISPLAY 0.340426 (-6105 4622);
PAINT GREEN (-6105 4622);
DISPLAY INVISIBLE (-6105 4622);
FORCEPROP 1 LAST PATH I32
J 0
(-6105 4602);
DISPLAY 0.340426 (-6105 4602);
PAINT GREEN (-6105 4602);
DISPLAY INVISIBLE (-6105 4602);
FORCEPROP 2 LAST CDS_LIB mstr_symbols
J 0
(-6150 4600);
PAINT MONO (-6150 4600);
DISPLAY INVISIBLE (-6150 4600);
FORCEPROP 1 LAST BODY_TYPE PLUMBING
J 0
(-6195 4557);
DISPLAY 0.340426 (-6195 4557);
PAINT GREEN (-6195 4557);
DISPLAY INVISIBLE (-6195 4557);
FORCEPROP 1 LAST HDL_POWER P3V3_STBY
J 0
(-6450 4475);
DISPLAY 0.872340 (-6450 4475);
PAINT ORANGE (-6450 4475);
DISPLAY INVISIBLE (-6450 4475);
FORCEADD RES..2
(-6150 4400);
FORCEPROP 1 LAST LOCATION R7E6
J 0
(-6105 4525);
DISPLAY 0.617021 (-6105 4525);
PAINT AQUA (-6105 4525);
FORCEPROP 1 LAST VALUE 10.0K
J 0
(-6105 4475);
DISPLAY 0.617021 (-6105 4475);
PAINT SKYBLUE (-6105 4475);
FORCEPROP 1 LAST TOLERANCE 1%
J 0
(-6105 4425);
DISPLAY 0.617021 (-6105 4425);
PAINT SKYBLUE (-6105 4425);
FORCEPROP 1 LAST PART_NUMBER G21796-016
J 0
(-6110 4275);
DISPLAY 0.617021 (-6110 4275);
PAINT BLUE (-6110 4275);
FORCEPROP 1 LAST MATERIAL CHIP
J 0
(-6110 4325);
DISPLAY 0.617021 (-6110 4325);
PAINT SKYBLUE (-6110 4325);
FORCEPROP 1 LAST WATTAGE 1/16W
J 0
(-6110 4375);
DISPLAY 0.617021 (-6110 4375);
PAINT SKYBLUE (-6110 4375);
FORCEPROP 1 LAST PACK_TYPE 0402
J 0
(-6110 4225);
DISPLAY 0.617021 (-6110 4225);
PAINT SKYBLUE (-6110 4225);
FORCEPROP 1 LASTPIN (-6150 4500) $PN 1
J 0
(-6145 4462);
DISPLAY 0.787234 (-6145 4462);
PAINT ORANGE (-6145 4462);
FORCEPROP 1 LASTPIN (-6150 4300) $PN 2
J 0
(-6145 4310);
DISPLAY 0.787234 (-6145 4310);
PAINT ORANGE (-6145 4310);
FORCEPROP 2 LAST ROOM CPLD
J 0
(-6100 4575);
DISPLAY 1.021277 (-6100 4575);
PAINT ORANGE (-6100 4575);
DISPLAY INVISIBLE (-6100 4575);
FORCEPROP 2 LAST BOM_COST CPLD
J 0
(-6100 4625);
DISPLAY 1.021277 (-6100 4625);
PAINT ORANGE (-6100 4625);
DISPLAY INVISIBLE (-6100 4625);
FORCEPROP 1 LAST PATH I33
J 0
(-6100 4575);
DISPLAY 0.978723 (-6100 4575);
PAINT WHITE (-6100 4575);
DISPLAY INVISIBLE (-6100 4575);
FORCEPROP 2 LAST CDS_LOCATION R7E6
J 0
(-6105 4525);
DISPLAY 0.617021 (-6105 4525);
PAINT AQUA (-6105 4525);
DISPLAY INVISIBLE (-6105 4525);
FORCEPROP 2 LAST CDS_LIB mstr_discrete
J 0
(-6150 4400);
PAINT MONO (-6150 4400);
DISPLAY INVISIBLE (-6150 4400);
FORCEPROP 2 LAST SEC 1
J 0
(-6100 4625);
PAINT MONO (-6100 4625);
DISPLAY INVISIBLE (-6100 4625);
FORCEPROP 2 LAST SEC_TYPE 0402
J 0
(-6100 4625);
DISPLAY 1.021277 (-6100 4625);
PAINT ORANGE (-6100 4625);
DISPLAY INVISIBLE (-6100 4625);
FORCEADD RES..2
(-5750 4400);
FORCEPROP 1 LAST VALUE 10.0K
J 0
(-5705 4475);
DISPLAY 0.617021 (-5705 4475);
PAINT SKYBLUE (-5705 4475);
FORCEPROP 1 LAST TOLERANCE 1%
J 0
(-5705 4425);
DISPLAY 0.617021 (-5705 4425);
PAINT SKYBLUE (-5705 4425);
FORCEPROP 1 LAST MATERIAL CHIP
J 0
(-5710 4325);
DISPLAY 0.617021 (-5710 4325);
PAINT SKYBLUE (-5710 4325);
FORCEPROP 1 LASTPIN (-5750 4500) $PN 1
J 0
(-5745 4462);
DISPLAY 0.787234 (-5745 4462);
PAINT ORANGE (-5745 4462);
FORCEPROP 1 LASTPIN (-5750 4300) $PN 2
J 0
(-5745 4310);
DISPLAY 0.787234 (-5745 4310);
PAINT ORANGE (-5745 4310);
FORCEPROP 1 LAST PACK_TYPE 0402
J 0
(-5710 4225);
DISPLAY 0.617021 (-5710 4225);
PAINT SKYBLUE (-5710 4225);
FORCEPROP 1 LAST WATTAGE 1/16W
J 0
(-5710 4375);
DISPLAY 0.617021 (-5710 4375);
PAINT SKYBLUE (-5710 4375);
FORCEPROP 1 LAST LOCATION R2R1
J 0
(-5705 4525);
DISPLAY 0.617021 (-5705 4525);
PAINT AQUA (-5705 4525);
FORCEPROP 1 LAST PART_NUMBER G21796-016
J 0
(-5710 4275);
DISPLAY 0.617021 (-5710 4275);
PAINT BLUE (-5710 4275);
FORCEPROP 2 LAST ROOM CPLD
J 0
(-5700 4575);
DISPLAY 1.021277 (-5700 4575);
PAINT ORANGE (-5700 4575);
DISPLAY INVISIBLE (-5700 4575);
FORCEPROP 2 LAST BOM_COST CPLD
J 0
(-5700 4625);
DISPLAY 1.021277 (-5700 4625);
PAINT ORANGE (-5700 4625);
DISPLAY INVISIBLE (-5700 4625);
FORCEPROP 1 LAST PATH I34
J 0
(-5700 4575);
DISPLAY 0.978723 (-5700 4575);
PAINT WHITE (-5700 4575);
DISPLAY INVISIBLE (-5700 4575);
FORCEPROP 2 LAST CDS_LOCATION R2R1
J 0
(-5705 4525);
DISPLAY 0.617021 (-5705 4525);
PAINT AQUA (-5705 4525);
DISPLAY INVISIBLE (-5705 4525);
FORCEPROP 2 LAST CDS_LIB mstr_discrete
J 0
(-5750 4400);
PAINT MONO (-5750 4400);
DISPLAY INVISIBLE (-5750 4400);
FORCEPROP 2 LAST SEC 1
J 0
(-5700 4625);
PAINT MONO (-5700 4625);
DISPLAY INVISIBLE (-5700 4625);
FORCEPROP 2 LAST SEC_TYPE 0402
J 0
(-5700 4625);
DISPLAY 1.021277 (-5700 4625);
PAINT ORANGE (-5700 4625);
DISPLAY INVISIBLE (-5700 4625);
FORCEADD P3V3_STBY..1
(-5750 4600);
FORCEPROP 3 LASTPIN (-5750 4550) SIG_NAME P3V3_STBY\g
J 0
(-5740 4560);
DISPLAY 0.659574 (-5740 4560);
PAINT MONO (-5740 4560);
DISPLAY INVISIBLE (-5740 4560);
FORCEPROP 1 LAST VOLTAGE 3.3V
J 0
(-5795 4557);
DISPLAY 0.340426 (-5795 4557);
PAINT SKYBLUE (-5795 4557);
DISPLAY INVISIBLE (-5795 4557);
FORCEPROP 1 LAST SIZE 1B
J 0
(-5705 4622);
DISPLAY 0.340426 (-5705 4622);
PAINT GREEN (-5705 4622);
DISPLAY INVISIBLE (-5705 4622);
FORCEPROP 1 LAST PATH I35
J 0
(-5705 4602);
DISPLAY 0.340426 (-5705 4602);
PAINT GREEN (-5705 4602);
DISPLAY INVISIBLE (-5705 4602);
FORCEPROP 2 LAST CDS_LIB mstr_symbols
J 0
(-5750 4600);
PAINT MONO (-5750 4600);
DISPLAY INVISIBLE (-5750 4600);
FORCEPROP 1 LAST BODY_TYPE PLUMBING
J 0
(-5795 4557);
DISPLAY 0.340426 (-5795 4557);
PAINT GREEN (-5795 4557);
DISPLAY INVISIBLE (-5795 4557);
FORCEPROP 1 LAST HDL_POWER P3V3_STBY
J 0
(-6050 4475);
DISPLAY 0.872340 (-6050 4475);
PAINT ORANGE (-6050 4475);
DISPLAY INVISIBLE (-6050 4475);
FORCEADD OFFPAGE..2
(-5100 4200);
FORCEPROP 2 LASTPIN (-5150 4200) SIG_NAME PU_RST_PERST_BIT0
J 2
(-5160 4210);
DISPLAY 0.617021 (-5160 4210);
PAINT ORANGE (-5160 4210);
FORCEPROP 2 LAST $XR0 190 
J 0
(-4911 4200);
DISPLAY 0.638298 (-4911 4200);
PAINT MONO (-4911 4200);
FORCEPROP 2 LAST CDS_LIB mstr_standard
J 0
(-5100 4200);
PAINT MONO (-5100 4200);
DISPLAY INVISIBLE (-5100 4200);
FORCEPROP 2 LAST PATH I36
J 0
(-4925 4275);
DISPLAY 1.021277 (-4925 4275);
PAINT ORANGE (-4925 4275);
DISPLAY INVISIBLE (-4925 4275);
FORCEPROP 1 LAST OFFPAGE TRUE
J 0
(-4775 4075);
DISPLAY 0.872340 (-4775 4075);
PAINT GREEN (-4775 4075);
DISPLAY INVISIBLE (-4775 4075);
FORCEPROP 1 LAST COMMENT_BODY TRUE
J 0
(-5145 4105);
DISPLAY 0.872340 (-5145 4105);
PAINT GREEN (-5145 4105);
DISPLAY INVISIBLE (-5145 4105);
FORCEADD OFFPAGE..2
(-5100 4100);
FORCEPROP 2 LASTPIN (-5150 4100) SIG_NAME PU_RST_PERST_BIT1
J 2
(-5160 4110);
DISPLAY 0.617021 (-5160 4110);
PAINT ORANGE (-5160 4110);
FORCEPROP 2 LAST $XR0 191 
J 0
(-4911 4100);
DISPLAY 0.638298 (-4911 4100);
PAINT MONO (-4911 4100);
FORCEPROP 2 LAST CDS_LIB mstr_standard
J 0
(-5100 4100);
PAINT MONO (-5100 4100);
DISPLAY INVISIBLE (-5100 4100);
FORCEPROP 2 LAST PATH I37
J 0
(-4925 4175);
DISPLAY 1.021277 (-4925 4175);
PAINT ORANGE (-4925 4175);
DISPLAY INVISIBLE (-4925 4175);
FORCEPROP 1 LAST OFFPAGE TRUE
J 0
(-4775 3975);
DISPLAY 0.872340 (-4775 3975);
PAINT GREEN (-4775 3975);
DISPLAY INVISIBLE (-4775 3975);
FORCEPROP 1 LAST COMMENT_BODY TRUE
J 0
(-5145 4005);
DISPLAY 0.872340 (-5145 4005);
PAINT GREEN (-5145 4005);
DISPLAY INVISIBLE (-5145 4005);
FORCEADD RES..2
(-6550 4400);
FORCEPROP 1 LASTPIN (-6550 4300) $PN 2
J 0
(-6545 4310);
DISPLAY 0.617021 (-6545 4310);
PAINT ORANGE (-6545 4310);
FORCEPROP 1 LAST LOCATION R7E5
J 0
(-6505 4525);
DISPLAY 0.617021 (-6505 4525);
PAINT AQUA (-6505 4525);
FORCEPROP 1 LAST PACK_TYPE 0402
J 0
(-6510 4225);
DISPLAY 0.617021 (-6510 4225);
PAINT SKYBLUE (-6510 4225);
FORCEPROP 1 LAST PART_NUMBER G21796-016
J 0
(-6510 4275);
DISPLAY 0.617021 (-6510 4275);
PAINT BLUE (-6510 4275);
FORCEPROP 1 LAST MATERIAL CHIP
J 0
(-6510 4325);
DISPLAY 0.617021 (-6510 4325);
PAINT SKYBLUE (-6510 4325);
FORCEPROP 1 LAST WATTAGE 1/16W
J 0
(-6510 4375);
DISPLAY 0.617021 (-6510 4375);
PAINT SKYBLUE (-6510 4375);
FORCEPROP 1 LAST TOLERANCE 1%
J 0
(-6505 4425);
DISPLAY 0.617021 (-6505 4425);
PAINT SKYBLUE (-6505 4425);
FORCEPROP 1 LASTPIN (-6550 4500) $PN 1
J 0
(-6545 4462);
DISPLAY 0.617021 (-6545 4462);
PAINT ORANGE (-6545 4462);
FORCEPROP 1 LAST VALUE 10.0K
J 0
(-6505 4475);
DISPLAY 0.617021 (-6505 4475);
PAINT SKYBLUE (-6505 4475);
FORCEPROP 2 LAST ROOM CPLD
J 0
(-6500 4575);
DISPLAY 1.021277 (-6500 4575);
PAINT ORANGE (-6500 4575);
DISPLAY INVISIBLE (-6500 4575);
FORCEPROP 2 LAST $SEC 1
J 0
(-6500 4625);
PAINT MONO (-6500 4625);
DISPLAY INVISIBLE (-6500 4625);
FORCEPROP 2 LAST CDS_SEC 1
J 0
(-6500 4625);
PAINT MONO (-6500 4625);
DISPLAY INVISIBLE (-6500 4625);
FORCEPROP 2 LAST BOM_COST CPLD
J 0
(-6500 4625);
DISPLAY 1.021277 (-6500 4625);
PAINT ORANGE (-6500 4625);
DISPLAY INVISIBLE (-6500 4625);
FORCEPROP 1 LAST PATH I38
J 0
(-6500 4575);
DISPLAY 0.978723 (-6500 4575);
PAINT WHITE (-6500 4575);
DISPLAY INVISIBLE (-6500 4575);
FORCEPROP 2 LAST CDS_LOCATION R7E5
J 0
(-6505 4525);
DISPLAY 0.617021 (-6505 4525);
PAINT AQUA (-6505 4525);
DISPLAY INVISIBLE (-6505 4525);
FORCEPROP 2 LAST CDS_LIB mstr_discrete
J 0
(-6550 4400);
PAINT MONO (-6550 4400);
DISPLAY INVISIBLE (-6550 4400);
FORCEADD P3V3_STBY..1
(-6550 4600);
FORCEPROP 3 LASTPIN (-6550 4550) SIG_NAME P3V3_STBY\g
J 0
(-6540 4560);
DISPLAY 0.659574 (-6540 4560);
PAINT MONO (-6540 4560);
DISPLAY INVISIBLE (-6540 4560);
FORCEPROP 1 LAST VOLTAGE 3.3V
J 0
(-6595 4557);
DISPLAY 0.340426 (-6595 4557);
PAINT SKYBLUE (-6595 4557);
DISPLAY INVISIBLE (-6595 4557);
FORCEPROP 1 LAST SIZE 1B
J 0
(-6505 4622);
DISPLAY 0.340426 (-6505 4622);
PAINT GREEN (-6505 4622);
DISPLAY INVISIBLE (-6505 4622);
FORCEPROP 1 LAST PATH I39
J 0
(-6505 4602);
DISPLAY 0.340426 (-6505 4602);
PAINT GREEN (-6505 4602);
DISPLAY INVISIBLE (-6505 4602);
FORCEPROP 2 LAST CDS_LIB mstr_symbols
J 0
(-6550 4600);
PAINT MONO (-6550 4600);
DISPLAY INVISIBLE (-6550 4600);
FORCEPROP 1 LAST BODY_TYPE PLUMBING
J 0
(-6595 4557);
DISPLAY 0.340426 (-6595 4557);
PAINT GREEN (-6595 4557);
DISPLAY INVISIBLE (-6595 4557);
FORCEPROP 1 LAST HDL_POWER P3V3_STBY
J 0
(-6850 4475);
DISPLAY 0.872340 (-6850 4475);
PAINT ORANGE (-6850 4475);
DISPLAY INVISIBLE (-6850 4475);
FORCEADD CAP_A..1
(-2175 1975);
FORCEPROP 1 LAST LOCATION C3R1
J 0
(-2125 2075);
DISPLAY 0.617021 (-2125 2075);
PAINT AQUA (-2125 2075);
FORCEPROP 1 LAST PART_NUMBER A36096-030
J 0
(-2125 1825);
DISPLAY 0.617021 (-2125 1825);
PAINT BLUE (-2125 1825);
FORCEPROP 1 LAST VALUE 0.1UF
J 0
(-2125 2025);
DISPLAY 0.617021 (-2125 2025);
PAINT SKYBLUE (-2125 2025);
FORCEPROP 1 LAST TOLERANCE 10%
J 0
(-2125 1925);
DISPLAY 0.617021 (-2125 1925);
PAINT SKYBLUE (-2125 1925);
FORCEPROP 1 LAST PACK_TYPE 0402V
J 0
(-2125 1775);
DISPLAY 0.617021 (-2125 1775);
PAINT SKYBLUE (-2125 1775);
FORCEPROP 1 LAST VOLTAGE 16V
J 0
(-2125 1975);
DISPLAY 0.617021 (-2125 1975);
PAINT SKYBLUE (-2125 1975);
FORCEPROP 1 LAST MATERIAL X7R
J 0
(-2125 1875);
DISPLAY 0.617021 (-2125 1875);
PAINT SKYBLUE (-2125 1875);
FORCEPROP 1 LASTPIN (-2175 2075) $PN 1
J 0
(-2165 2055);
DISPLAY 0.617021 (-2165 2055);
PAINT ORANGE (-2165 2055);
FORCEPROP 1 LASTPIN (-2175 1875) $PN 2
J 0
(-2165 1855);
DISPLAY 0.617021 (-2165 1855);
PAINT ORANGE (-2165 1855);
FORCEPROP 2 LAST ROOM CPLD
J 0
(-2125 2125);
DISPLAY 1.361702 (-2125 2125);
PAINT ORANGE (-2125 2125);
DISPLAY INVISIBLE (-2125 2125);
FORCEPROP 2 LAST CDS_SEC 1
J 0
(-2125 2175);
PAINT MONO (-2125 2175);
DISPLAY INVISIBLE (-2125 2175);
FORCEPROP 2 LAST BOM_COST CPLD
J 0
(-2125 2175);
DISPLAY 1.361702 (-2125 2175);
PAINT ORANGE (-2125 2175);
DISPLAY INVISIBLE (-2125 2175);
FORCEPROP 2 LAST $SEC 1
J 0
(-2125 2175);
PAINT MONO (-2125 2175);
DISPLAY INVISIBLE (-2125 2175);
FORCEPROP 2 LAST SIGNAL_MODEL DEFAULT_CAPACITOR_100000pF_2_1
J 0
(-2125 2175);
PAINT MONO (-2125 2175);
DISPLAY INVISIBLE (-2125 2175);
FORCEPROP 2 LAST CDS_LOCATION C3R1
J 0
(-2125 2075);
DISPLAY 0.617021 (-2125 2075);
PAINT AQUA (-2125 2075);
DISPLAY INVISIBLE (-2125 2075);
FORCEPROP 1 LAST PATH I4
J 0
(-2125 2125);
DISPLAY 0.978723 (-2125 2125);
PAINT WHITE (-2125 2125);
DISPLAY INVISIBLE (-2125 2125);
FORCEPROP 2 LAST CDS_LIB dev_discrete
J 0
(-2175 1975);
PAINT ORANGE (-2175 1975);
DISPLAY INVISIBLE (-2175 1975);
FORCEADD OFFPAGE..2
(-5100 4000);
FORCEPROP 2 LASTPIN (-5150 4000) SIG_NAME PU_THERMTRIP_FORCE_N
J 2
(-5160 4010);
DISPLAY 0.617021 (-5160 4010);
PAINT ORANGE (-5160 4010);
FORCEPROP 2 LAST $XR0 191 
J 0
(-4911 4000);
DISPLAY 0.638298 (-4911 4000);
PAINT MONO (-4911 4000);
FORCEPROP 2 LAST CDS_LIB mstr_standard
J 0
(-5100 4000);
PAINT MONO (-5100 4000);
DISPLAY INVISIBLE (-5100 4000);
FORCEPROP 2 LAST PATH I40
J 0
(-4925 4075);
DISPLAY 1.021277 (-4925 4075);
PAINT ORANGE (-4925 4075);
DISPLAY INVISIBLE (-4925 4075);
FORCEPROP 1 LAST OFFPAGE TRUE
J 0
(-4775 3875);
DISPLAY 0.872340 (-4775 3875);
PAINT GREEN (-4775 3875);
DISPLAY INVISIBLE (-4775 3875);
FORCEPROP 1 LAST COMMENT_BODY TRUE
J 0
(-5145 3905);
DISPLAY 0.872340 (-5145 3905);
PAINT GREEN (-5145 3905);
DISPLAY INVISIBLE (-5145 3905);
FORCEADD RES..2
(-6950 4400);
FORCEPROP 1 LAST VALUE 10.0K
J 0
(-6905 4475);
DISPLAY 0.617021 (-6905 4475);
PAINT SKYBLUE (-6905 4475);
FORCEPROP 1 LAST TOLERANCE 1%
J 0
(-6905 4425);
DISPLAY 0.617021 (-6905 4425);
PAINT SKYBLUE (-6905 4425);
FORCEPROP 1 LAST LOCATION R2R3
J 0
(-6905 4525);
DISPLAY 0.617021 (-6905 4525);
PAINT AQUA (-6905 4525);
FORCEPROP 1 LASTPIN (-6950 4500) $PN 1
J 0
(-6945 4462);
DISPLAY 0.617021 (-6945 4462);
PAINT ORANGE (-6945 4462);
FORCEPROP 1 LASTPIN (-6950 4300) $PN 2
J 0
(-6945 4310);
DISPLAY 0.617021 (-6945 4310);
PAINT ORANGE (-6945 4310);
FORCEPROP 1 LAST MATERIAL CHIP
J 0
(-6910 4325);
DISPLAY 0.617021 (-6910 4325);
PAINT SKYBLUE (-6910 4325);
FORCEPROP 1 LAST WATTAGE 1/16W
J 0
(-6910 4375);
DISPLAY 0.617021 (-6910 4375);
PAINT SKYBLUE (-6910 4375);
FORCEPROP 1 LAST PACK_TYPE 0402
J 0
(-6910 4225);
DISPLAY 0.617021 (-6910 4225);
PAINT SKYBLUE (-6910 4225);
FORCEPROP 1 LAST PART_NUMBER G21796-016
J 0
(-6910 4275);
DISPLAY 0.617021 (-6910 4275);
PAINT BLUE (-6910 4275);
FORCEPROP 2 LAST ROOM CPLD
J 0
(-6900 4575);
DISPLAY 1.021277 (-6900 4575);
PAINT ORANGE (-6900 4575);
DISPLAY INVISIBLE (-6900 4575);
FORCEPROP 2 LAST $SEC 1
J 0
(-6900 4625);
PAINT MONO (-6900 4625);
DISPLAY INVISIBLE (-6900 4625);
FORCEPROP 2 LAST CDS_SEC 1
J 0
(-6900 4625);
PAINT MONO (-6900 4625);
DISPLAY INVISIBLE (-6900 4625);
FORCEPROP 2 LAST BOM_COST CPLD
J 0
(-6900 4625);
DISPLAY 1.021277 (-6900 4625);
PAINT ORANGE (-6900 4625);
DISPLAY INVISIBLE (-6900 4625);
FORCEPROP 1 LAST PATH I41
J 0
(-6900 4575);
DISPLAY 0.978723 (-6900 4575);
PAINT WHITE (-6900 4575);
DISPLAY INVISIBLE (-6900 4575);
FORCEPROP 2 LAST CDS_LOCATION R2R3
J 0
(-6905 4525);
DISPLAY 0.617021 (-6905 4525);
PAINT AQUA (-6905 4525);
DISPLAY INVISIBLE (-6905 4525);
FORCEPROP 2 LAST CDS_LIB mstr_discrete
J 0
(-6950 4400);
PAINT MONO (-6950 4400);
DISPLAY INVISIBLE (-6950 4400);
FORCEADD P3V3_STBY..1
(-6950 4600);
FORCEPROP 3 LASTPIN (-6950 4550) SIG_NAME P3V3_STBY\g
J 0
(-6940 4560);
DISPLAY 0.659574 (-6940 4560);
PAINT MONO (-6940 4560);
DISPLAY INVISIBLE (-6940 4560);
FORCEPROP 1 LAST VOLTAGE 3.3V
J 0
(-6995 4557);
DISPLAY 0.340426 (-6995 4557);
PAINT SKYBLUE (-6995 4557);
DISPLAY INVISIBLE (-6995 4557);
FORCEPROP 1 LAST SIZE 1B
J 0
(-6905 4622);
DISPLAY 0.340426 (-6905 4622);
PAINT GREEN (-6905 4622);
DISPLAY INVISIBLE (-6905 4622);
FORCEPROP 1 LAST PATH I42
J 0
(-6905 4602);
DISPLAY 0.340426 (-6905 4602);
PAINT GREEN (-6905 4602);
DISPLAY INVISIBLE (-6905 4602);
FORCEPROP 2 LAST CDS_LIB mstr_symbols
J 0
(-6950 4600);
PAINT MONO (-6950 4600);
DISPLAY INVISIBLE (-6950 4600);
FORCEPROP 1 LAST BODY_TYPE PLUMBING
J 0
(-6995 4557);
DISPLAY 0.340426 (-6995 4557);
PAINT GREEN (-6995 4557);
DISPLAY INVISIBLE (-6995 4557);
FORCEPROP 1 LAST HDL_POWER P3V3_STBY
J 0
(-7250 4475);
DISPLAY 0.872340 (-7250 4475);
PAINT ORANGE (-7250 4475);
DISPLAY INVISIBLE (-7250 4475);
FORCEADD OFFPAGE..2
(-5100 3900);
FORCEPROP 2 LASTPIN (-5150 3900) SIG_NAME FM_PLD_DEBUG_MODE_N
J 2
(-5160 3910);
DISPLAY 0.617021 (-5160 3910);
PAINT ORANGE (-5160 3910);
FORCEPROP 2 LAST $XR0 191 
J 0
(-4911 3900);
DISPLAY 0.638298 (-4911 3900);
PAINT MONO (-4911 3900);
FORCEPROP 2 LAST CDS_LIB mstr_standard
J 0
(-5100 3900);
PAINT MONO (-5100 3900);
DISPLAY INVISIBLE (-5100 3900);
FORCEPROP 2 LAST PATH I45
J 0
(-4925 3975);
DISPLAY 1.021277 (-4925 3975);
PAINT ORANGE (-4925 3975);
DISPLAY INVISIBLE (-4925 3975);
FORCEPROP 1 LAST OFFPAGE TRUE
J 0
(-4775 3775);
DISPLAY 0.872340 (-4775 3775);
PAINT GREEN (-4775 3775);
DISPLAY INVISIBLE (-4775 3775);
FORCEPROP 1 LAST COMMENT_BODY TRUE
J 0
(-5145 3805);
DISPLAY 0.872340 (-5145 3805);
PAINT GREEN (-5145 3805);
DISPLAY INVISIBLE (-5145 3805);
FORCEADD RES..2
(-6150 2800);
FORCEPROP 1 LAST LOCATION R3R16
J 0
(-6105 2925);
DISPLAY 0.617021 (-6105 2925);
PAINT AQUA (-6105 2925);
FORCEPROP 1 LAST PART_NUMBER G21796-072
J 0
(-6110 2675);
DISPLAY 0.617021 (-6110 2675);
PAINT BLUE (-6110 2675);
FORCEPROP 1 LAST VALUE 4.75K
J 0
(-6105 2875);
DISPLAY 0.617021 (-6105 2875);
PAINT SKYBLUE (-6105 2875);
FORCEPROP 1 LAST TOLERANCE 1%
J 0
(-6105 2825);
DISPLAY 0.617021 (-6105 2825);
PAINT SKYBLUE (-6105 2825);
FORCEPROP 1 LAST PACK_TYPE 0402
J 0
(-6110 2625);
DISPLAY 0.617021 (-6110 2625);
PAINT SKYBLUE (-6110 2625);
FORCEPROP 1 LAST WATTAGE 1/16W
J 0
(-6110 2775);
DISPLAY 0.617021 (-6110 2775);
PAINT SKYBLUE (-6110 2775);
FORCEPROP 1 LASTPIN (-6150 2900) $PN 1
J 0
(-6145 2862);
DISPLAY 0.617021 (-6145 2862);
PAINT ORANGE (-6145 2862);
FORCEPROP 1 LASTPIN (-6150 2700) $PN 2
J 0
(-6145 2710);
DISPLAY 0.617021 (-6145 2710);
PAINT ORANGE (-6145 2710);
FORCEPROP 1 LAST MATERIAL CHIP
J 0
(-6110 2725);
DISPLAY 0.617021 (-6110 2725);
PAINT SKYBLUE (-6110 2725);
FORCEPROP 0 LAST ROOM CPLD
J 0
(-6100 3025);
DISPLAY 1.021277 (-6100 3025);
PAINT ORANGE (-6100 3025);
DISPLAY INVISIBLE (-6100 3025);
FORCEPROP 0 LAST BOM_COST CPLD
J 0
(-6100 3125);
DISPLAY 1.021277 (-6100 3125);
PAINT ORANGE (-6100 3125);
DISPLAY INVISIBLE (-6100 3125);
FORCEPROP 1 LAST PATH I48
J 0
(-6100 2975);
DISPLAY 0.978723 (-6100 2975);
PAINT WHITE (-6100 2975);
DISPLAY INVISIBLE (-6100 2975);
FORCEPROP 2 LAST SEC 1
J 0
(-6100 3025);
DISPLAY 0.680851 (-6100 3025);
PAINT MONO (-6100 3025);
DISPLAY INVISIBLE (-6100 3025);
FORCEPROP 2 LAST SEC_TYPE 0402
J 0
(-6100 3025);
DISPLAY 1.021277 (-6100 3025);
PAINT ORANGE (-6100 3025);
DISPLAY INVISIBLE (-6100 3025);
FORCEPROP 2 LAST CDS_LIB mstr_discrete
J 0
(-6150 2800);
PAINT ORANGE (-6150 2800);
DISPLAY INVISIBLE (-6150 2800);
FORCEADD RES..2
(-5750 2800);
FORCEPROP 1 LAST LOCATION R6M9
J 0
(-5705 2925);
DISPLAY 0.617021 (-5705 2925);
PAINT AQUA (-5705 2925);
FORCEPROP 1 LAST PART_NUMBER G21796-072
J 0
(-5710 2675);
DISPLAY 0.617021 (-5710 2675);
PAINT BLUE (-5710 2675);
FORCEPROP 1 LAST VALUE 4.75K
J 0
(-5705 2875);
DISPLAY 0.617021 (-5705 2875);
PAINT SKYBLUE (-5705 2875);
FORCEPROP 1 LAST TOLERANCE 1%
J 0
(-5705 2825);
DISPLAY 0.617021 (-5705 2825);
PAINT SKYBLUE (-5705 2825);
FORCEPROP 1 LAST PACK_TYPE 0402
J 0
(-5710 2625);
DISPLAY 0.617021 (-5710 2625);
PAINT SKYBLUE (-5710 2625);
FORCEPROP 1 LAST MATERIAL CHIP
J 0
(-5710 2725);
DISPLAY 0.617021 (-5710 2725);
PAINT SKYBLUE (-5710 2725);
FORCEPROP 1 LAST WATTAGE 1/16W
J 0
(-5710 2775);
DISPLAY 0.617021 (-5710 2775);
PAINT SKYBLUE (-5710 2775);
FORCEPROP 1 LASTPIN (-5750 2900) $PN 1
J 0
(-5745 2862);
DISPLAY 0.617021 (-5745 2862);
PAINT ORANGE (-5745 2862);
FORCEPROP 1 LASTPIN (-5750 2700) $PN 2
J 0
(-5745 2710);
DISPLAY 0.617021 (-5745 2710);
PAINT ORANGE (-5745 2710);
FORCEPROP 2 LAST ROOM CPLD
J 0
(-5700 2975);
DISPLAY 1.021277 (-5700 2975);
PAINT ORANGE (-5700 2975);
DISPLAY INVISIBLE (-5700 2975);
FORCEPROP 2 LAST SEC 1
J 0
(-5700 3025);
DISPLAY 0.680851 (-5700 3025);
PAINT MONO (-5700 3025);
DISPLAY INVISIBLE (-5700 3025);
FORCEPROP 2 LAST SEC_TYPE 0402
J 0
(-5700 3025);
DISPLAY 1.021277 (-5700 3025);
PAINT ORANGE (-5700 3025);
DISPLAY INVISIBLE (-5700 3025);
FORCEPROP 1 LAST PATH I49
J 0
(-5700 2975);
DISPLAY 0.978723 (-5700 2975);
PAINT WHITE (-5700 2975);
DISPLAY INVISIBLE (-5700 2975);
FORCEPROP 2 LAST BOM_COST CPLD
J 0
(-5700 3025);
DISPLAY 1.021277 (-5700 3025);
PAINT ORANGE (-5700 3025);
DISPLAY INVISIBLE (-5700 3025);
FORCEPROP 2 LAST CDS_LIB mstr_discrete
J 0
(-5750 2800);
PAINT ORANGE (-5750 2800);
DISPLAY INVISIBLE (-5750 2800);
FORCEADD GND..1
(-1100 3100);
FORCEPROP 3 LASTPIN (-1100 3150) SIG_NAME GND\g
J 0
(-1090 3160);
DISPLAY 0.659574 (-1090 3160);
PAINT MONO (-1090 3160);
DISPLAY INVISIBLE (-1090 3160);
FORCEPROP 1 LAST VOLTAGE 0.0V
J 0
(-1145 3057);
DISPLAY 0.340426 (-1145 3057);
PAINT SKYBLUE (-1145 3057);
DISPLAY INVISIBLE (-1145 3057);
FORCEPROP 2 LAST ROOM CPLD
J 0
(-1325 3175);
DISPLAY 1.361702 (-1325 3175);
PAINT ORANGE (-1325 3175);
DISPLAY INVISIBLE (-1325 3175);
FORCEPROP 2 LAST CDS_LIB mstr_symbols
J 0
(-1100 3100);
PAINT ORANGE (-1100 3100);
DISPLAY INVISIBLE (-1100 3100);
FORCEPROP 1 LAST PATH I5
J 0
(-1025 3100);
DISPLAY 0.872340 (-1025 3100);
PAINT AQUA (-1025 3100);
DISPLAY INVISIBLE (-1025 3100);
FORCEPROP 2 LAST BOM_COST CPLD
J 0
(-1325 3225);
DISPLAY 1.361702 (-1325 3225);
PAINT ORANGE (-1325 3225);
DISPLAY INVISIBLE (-1325 3225);
FORCEPROP 1 LAST SIZE 1B
J 0
(-1025 3050);
DISPLAY 1.170213 (-1025 3050);
PAINT AQUA (-1025 3050);
DISPLAY INVISIBLE (-1025 3050);
FORCEPROP 1 LAST BODY_TYPE PLUMBING
J 0
(-1145 3057);
DISPLAY 0.340426 (-1145 3057);
PAINT GREEN (-1145 3057);
DISPLAY INVISIBLE (-1145 3057);
FORCEPROP 1 LAST HDL_POWER GND
J 0
(-1100 3250);
DISPLAY 1.170213 (-1100 3250);
PAINT GREEN (-1100 3250);
DISPLAY INVISIBLE (-1100 3250);
FORCEADD OFFPAGE..2
(-5100 2500);
FORCEPROP 2 LASTPIN (-5150 2500) SIG_NAME RST_CD_CPU0_POR_N
J 2
(-5160 2510);
DISPLAY 0.617021 (-5160 2510);
PAINT ORANGE (-5160 2510);
FORCEPROP 2 LAST $XR1 29 
J 0
(-4791 2500);
DISPLAY 0.638298 (-4791 2500);
PAINT MONO (-4791 2500);
FORCEPROP 2 LAST $XR0 190 
J 0
(-4911 2500);
DISPLAY 0.638298 (-4911 2500);
PAINT MONO (-4911 2500);
FORCEPROP 2 LAST CDS_LIB mstr_standard
J 0
(-5100 2500);
PAINT ORANGE (-5100 2500);
DISPLAY INVISIBLE (-5100 2500);
FORCEPROP 2 LAST PATH I50
J 0
(-4925 2575);
DISPLAY 1.021277 (-4925 2575);
PAINT ORANGE (-4925 2575);
DISPLAY INVISIBLE (-4925 2575);
FORCEPROP 1 LAST OFFPAGE TRUE
J 0
(-4775 2375);
DISPLAY 0.872340 (-4775 2375);
PAINT GREEN (-4775 2375);
DISPLAY INVISIBLE (-4775 2375);
FORCEPROP 1 LAST COMMENT_BODY TRUE
J 0
(-5145 2405);
DISPLAY 0.872340 (-5145 2405);
PAINT GREEN (-5145 2405);
DISPLAY INVISIBLE (-5145 2405);
FORCEADD OFFPAGE..2
(-5100 2600);
FORCEPROP 2 LASTPIN (-5150 2600) SIG_NAME RST_CD_CPU1_POR_N
J 2
(-5160 2610);
DISPLAY 0.617021 (-5160 2610);
PAINT ORANGE (-5160 2610);
FORCEPROP 2 LAST $XR1 63 
J 0
(-4791 2600);
DISPLAY 0.638298 (-4791 2600);
PAINT MONO (-4791 2600);
FORCEPROP 2 LAST $XR0 190 
J 0
(-4911 2600);
DISPLAY 0.638298 (-4911 2600);
PAINT MONO (-4911 2600);
FORCEPROP 2 LAST CDS_LIB mstr_standard
J 0
(-5100 2600);
PAINT ORANGE (-5100 2600);
DISPLAY INVISIBLE (-5100 2600);
FORCEPROP 2 LAST PATH I51
J 0
(-4925 2675);
DISPLAY 1.021277 (-4925 2675);
PAINT ORANGE (-4925 2675);
DISPLAY INVISIBLE (-4925 2675);
FORCEPROP 1 LAST OFFPAGE TRUE
J 0
(-4775 2475);
DISPLAY 0.872340 (-4775 2475);
PAINT GREEN (-4775 2475);
DISPLAY INVISIBLE (-4775 2475);
FORCEPROP 1 LAST COMMENT_BODY TRUE
J 0
(-5145 2505);
DISPLAY 0.872340 (-5145 2505);
PAINT GREEN (-5145 2505);
DISPLAY INVISIBLE (-5145 2505);
FORCEADD PVPP_ABC..1
(-6150 3000);
FORCEPROP 3 LASTPIN (-6150 2950) SIG_NAME PVPP_ABC\g
J 0
(-6140 2960);
DISPLAY 0.659574 (-6140 2960);
PAINT MONO (-6140 2960);
DISPLAY INVISIBLE (-6140 2960);
FORCEPROP 1 LAST VOLTAGE 2.5V
J 0
(-6195 2957);
DISPLAY 0.340426 (-6195 2957);
PAINT SKYBLUE (-6195 2957);
DISPLAY INVISIBLE (-6195 2957);
FORCEPROP 2 LAST ROOM PVPP_KLM_VR
J 0
(-5900 3100);
PAINT ORANGE (-5900 3100);
DISPLAY INVISIBLE (-5900 3100);
FORCEPROP 2 LAST BOM_COST PVPP_KLM_VR
J 0
(-6075 3100);
PAINT MONO (-6075 3100);
DISPLAY INVISIBLE (-6075 3100);
FORCEPROP 1 LAST PATH I52
J 0
(-6100 3025);
DISPLAY 0.872340 (-6100 3025);
PAINT AQUA (-6100 3025);
DISPLAY INVISIBLE (-6100 3025);
FORCEPROP 2 LAST CDS_LIB mstr_symbols
J 0
(-6150 3000);
PAINT ORANGE (-6150 3000);
DISPLAY INVISIBLE (-6150 3000);
FORCEPROP 1 LAST BODY_TYPE PLUMBING
J 0
(-6195 2957);
DISPLAY 0.340426 (-6195 2957);
PAINT GREEN (-6195 2957);
DISPLAY INVISIBLE (-6195 2957);
FORCEPROP 1 LAST HDL_POWER PVPP_ABC
J 1
(-6150 3050);
DISPLAY 0.872340 (-6150 3050);
PAINT GREEN (-6150 3050);
DISPLAY INVISIBLE (-6150 3050);
FORCEADD OFFPAGE..2
(-5100 3800);
FORCEPROP 2 LASTPIN (-5150 3800) SIG_NAME RST_RSMRST_N
J 2
(-5160 3810);
DISPLAY 0.617021 (-5160 3810);
PAINT ORANGE (-5160 3810);
FORCEPROP 2 LAST $XR3 147 
J 0
(-4551 3800);
DISPLAY 0.638298 (-4551 3800);
PAINT MONO (-4551 3800);
FORCEPROP 2 LAST $XR2 118 
J 0
(-4671 3800);
DISPLAY 0.638298 (-4671 3800);
PAINT MONO (-4671 3800);
FORCEPROP 2 LAST $XR1 111 
J 0
(-4791 3800);
DISPLAY 0.638298 (-4791 3800);
PAINT MONO (-4791 3800);
FORCEPROP 2 LAST $XR0 190 
J 0
(-4911 3800);
DISPLAY 0.638298 (-4911 3800);
PAINT MONO (-4911 3800);
FORCEPROP 2 LAST CDS_LIB mstr_standard
J 0
(-5100 3800);
PAINT ORANGE (-5100 3800);
DISPLAY INVISIBLE (-5100 3800);
FORCEPROP 2 LAST PATH I54
J 0
(-4925 3875);
DISPLAY 1.021277 (-4925 3875);
PAINT ORANGE (-4925 3875);
DISPLAY INVISIBLE (-4925 3875);
FORCEPROP 1 LAST OFFPAGE TRUE
J 0
(-4775 3675);
DISPLAY 0.872340 (-4775 3675);
PAINT GREEN (-4775 3675);
DISPLAY INVISIBLE (-4775 3675);
FORCEPROP 1 LAST COMMENT_BODY TRUE
J 0
(-5145 3705);
DISPLAY 0.872340 (-5145 3705);
PAINT GREEN (-5145 3705);
DISPLAY INVISIBLE (-5145 3705);
FORCEADD RES..2
(-7350 4400);
FORCEPROP 1 LAST LOCATION R7E18
J 0
(-7305 4525);
DISPLAY 0.617021 (-7305 4525);
PAINT AQUA (-7305 4525);
FORCEPROP 1 LAST VALUE 4.75K
J 0
(-7305 4475);
DISPLAY 0.617021 (-7305 4475);
PAINT SKYBLUE (-7305 4475);
FORCEPROP 1 LAST PART_NUMBER G21796-072
J 0
(-7310 4275);
DISPLAY 0.617021 (-7310 4275);
PAINT BLUE (-7310 4275);
FORCEPROP 1 LAST WATTAGE 1/16W
J 0
(-7310 4375);
DISPLAY 0.617021 (-7310 4375);
PAINT SKYBLUE (-7310 4375);
FORCEPROP 1 LASTPIN (-7350 4300) $PN 2
J 0
(-7345 4310);
DISPLAY 0.787234 (-7345 4310);
PAINT ORANGE (-7345 4310);
FORCEPROP 1 LAST TOLERANCE 1%
J 0
(-7305 4425);
DISPLAY 0.617021 (-7305 4425);
PAINT SKYBLUE (-7305 4425);
FORCEPROP 1 LASTPIN (-7350 4500) $PN 1
J 0
(-7345 4462);
DISPLAY 0.787234 (-7345 4462);
PAINT ORANGE (-7345 4462);
FORCEPROP 0 LAST POP NOPOP
J 0
(-7300 4175);
DISPLAY 0.808511 (-7300 4175);
PAINT RED (-7300 4175);
FORCEPROP 1 LAST MATERIAL CHIP
J 0
(-7310 4325);
DISPLAY 0.617021 (-7310 4325);
PAINT SKYBLUE (-7310 4325);
FORCEPROP 1 LAST PACK_TYPE 0402
J 0
(-7310 4225);
DISPLAY 0.617021 (-7310 4225);
PAINT SKYBLUE (-7310 4225);
FORCEPROP 0 LAST ROOM CPLD
J 0
(-7300 4625);
DISPLAY 1.021277 (-7300 4625);
PAINT ORANGE (-7300 4625);
DISPLAY INVISIBLE (-7300 4625);
FORCEPROP 0 LAST BOM_COST CPLD
J 0
(-7300 4725);
DISPLAY 1.021277 (-7300 4725);
PAINT ORANGE (-7300 4725);
DISPLAY INVISIBLE (-7300 4725);
FORCEPROP 1 LAST PATH I55
J 0
(-7300 4575);
DISPLAY 0.978723 (-7300 4575);
PAINT WHITE (-7300 4575);
DISPLAY INVISIBLE (-7300 4575);
FORCEPROP 2 LAST CDS_LIB mstr_discrete
J 0
(-7350 4400);
PAINT ORANGE (-7350 4400);
DISPLAY INVISIBLE (-7350 4400);
FORCEPROP 2 LAST SEC 1
J 0
(-7300 4625);
PAINT MONO (-7300 4625);
DISPLAY INVISIBLE (-7300 4625);
FORCEPROP 2 LAST SEC_TYPE 0402
J 0
(-7300 4625);
DISPLAY 1.021277 (-7300 4625);
PAINT ORANGE (-7300 4625);
DISPLAY INVISIBLE (-7300 4625);
FORCEADD P3V3_STBY..1
(-7350 4600);
FORCEPROP 3 LASTPIN (-7350 4550) SIG_NAME P3V3_STBY\g
J 0
(-7340 4560);
DISPLAY 0.659574 (-7340 4560);
PAINT MONO (-7340 4560);
DISPLAY INVISIBLE (-7340 4560);
FORCEPROP 1 LAST VOLTAGE 3.3V
J 0
(-7395 4557);
DISPLAY 0.340426 (-7395 4557);
PAINT SKYBLUE (-7395 4557);
DISPLAY INVISIBLE (-7395 4557);
FORCEPROP 1 LAST SIZE 1B
J 0
(-7305 4622);
DISPLAY 0.340426 (-7305 4622);
PAINT GREEN (-7305 4622);
DISPLAY INVISIBLE (-7305 4622);
FORCEPROP 1 LAST PATH I56
J 0
(-7305 4602);
DISPLAY 0.340426 (-7305 4602);
PAINT GREEN (-7305 4602);
DISPLAY INVISIBLE (-7305 4602);
FORCEPROP 2 LAST CDS_LIB mstr_symbols
J 0
(-7350 4600);
PAINT ORANGE (-7350 4600);
DISPLAY INVISIBLE (-7350 4600);
FORCEPROP 1 LAST BODY_TYPE PLUMBING
J 0
(-7395 4557);
DISPLAY 0.340426 (-7395 4557);
PAINT GREEN (-7395 4557);
DISPLAY INVISIBLE (-7395 4557);
FORCEPROP 1 LAST HDL_POWER P3V3_STBY
J 0
(-7650 4475);
DISPLAY 0.872340 (-7650 4475);
PAINT ORANGE (-7650 4475);
DISPLAY INVISIBLE (-7650 4475);
FORCEADD RES..2
(-7750 4400);
FORCEPROP 1 LAST WATTAGE 1/16W
J 0
(-7710 4375);
DISPLAY 0.617021 (-7710 4375);
PAINT SKYBLUE (-7710 4375);
FORCEPROP 1 LASTPIN (-7750 4300) $PN 2
J 0
(-7745 4310);
DISPLAY 0.787234 (-7745 4310);
PAINT ORANGE (-7745 4310);
FORCEPROP 1 LAST TOLERANCE 1%
J 0
(-7705 4425);
DISPLAY 0.617021 (-7705 4425);
PAINT SKYBLUE (-7705 4425);
FORCEPROP 1 LASTPIN (-7750 4500) $PN 1
J 0
(-7745 4462);
DISPLAY 0.787234 (-7745 4462);
PAINT ORANGE (-7745 4462);
FORCEPROP 1 LAST VALUE 1.00K
J 0
(-7705 4475);
DISPLAY 0.617021 (-7705 4475);
PAINT SKYBLUE (-7705 4475);
FORCEPROP 1 LAST LOCATION R7E19
J 0
(-7705 4525);
DISPLAY 0.617021 (-7705 4525);
PAINT AQUA (-7705 4525);
FORCEPROP 1 LAST PART_NUMBER G21796-026
J 0
(-7710 4275);
DISPLAY 0.617021 (-7710 4275);
PAINT BLUE (-7710 4275);
FORCEPROP 1 LAST PACK_TYPE 0402
J 0
(-7710 4225);
DISPLAY 0.617021 (-7710 4225);
PAINT SKYBLUE (-7710 4225);
FORCEPROP 1 LAST MATERIAL EMPTY
J 0
(-7710 4325);
DISPLAY 0.617021 (-7710 4325);
PAINT RED (-7710 4325);
FORCEPROP 2 LAST ROOM CPLD
J 0
(-7700 4575);
DISPLAY 1.021277 (-7700 4575);
PAINT ORANGE (-7700 4575);
DISPLAY INVISIBLE (-7700 4575);
FORCEPROP 2 LAST BOM_COST CPLD
J 0
(-7700 4625);
DISPLAY 1.021277 (-7700 4625);
PAINT ORANGE (-7700 4625);
DISPLAY INVISIBLE (-7700 4625);
FORCEPROP 1 LAST PATH I57
J 0
(-7700 4575);
DISPLAY 0.978723 (-7700 4575);
PAINT WHITE (-7700 4575);
DISPLAY INVISIBLE (-7700 4575);
FORCEPROP 2 LAST CDS_LIB mstr_discrete
J 0
(-7750 4400);
PAINT ORANGE (-7750 4400);
DISPLAY INVISIBLE (-7750 4400);
FORCEPROP 2 LAST SEC 1
J 0
(-7700 4625);
PAINT MONO (-7700 4625);
DISPLAY INVISIBLE (-7700 4625);
FORCEPROP 2 LAST SEC_TYPE 0402
J 0
(-7700 4625);
DISPLAY 1.021277 (-7700 4625);
PAINT ORANGE (-7700 4625);
DISPLAY INVISIBLE (-7700 4625);
FORCEADD P3V3_STBY..1
(-7750 4600);
FORCEPROP 3 LASTPIN (-7750 4550) SIG_NAME P3V3_STBY\g
J 0
(-7740 4560);
DISPLAY 0.659574 (-7740 4560);
PAINT MONO (-7740 4560);
DISPLAY INVISIBLE (-7740 4560);
FORCEPROP 1 LAST VOLTAGE 3.3V
J 0
(-7795 4557);
DISPLAY 0.340426 (-7795 4557);
PAINT SKYBLUE (-7795 4557);
DISPLAY INVISIBLE (-7795 4557);
FORCEPROP 1 LAST SIZE 1B
J 0
(-7705 4622);
DISPLAY 0.340426 (-7705 4622);
PAINT GREEN (-7705 4622);
DISPLAY INVISIBLE (-7705 4622);
FORCEPROP 1 LAST PATH I58
J 0
(-7705 4602);
DISPLAY 0.340426 (-7705 4602);
PAINT GREEN (-7705 4602);
DISPLAY INVISIBLE (-7705 4602);
FORCEPROP 2 LAST CDS_LIB mstr_symbols
J 0
(-7750 4600);
PAINT ORANGE (-7750 4600);
DISPLAY INVISIBLE (-7750 4600);
FORCEPROP 1 LAST BODY_TYPE PLUMBING
J 0
(-7795 4557);
DISPLAY 0.340426 (-7795 4557);
PAINT GREEN (-7795 4557);
DISPLAY INVISIBLE (-7795 4557);
FORCEPROP 1 LAST HDL_POWER P3V3_STBY
J 0
(-8050 4475);
DISPLAY 0.872340 (-8050 4475);
PAINT ORANGE (-8050 4475);
DISPLAY INVISIBLE (-8050 4475);
FORCEADD RES..2
(-7750 3500);
FORCEPROP 1 LAST LOCATION R7E20
J 0
(-7705 3625);
DISPLAY 0.617021 (-7705 3625);
PAINT AQUA (-7705 3625);
FORCEPROP 1 LAST VALUE 1.00K
J 0
(-7705 3575);
DISPLAY 0.617021 (-7705 3575);
PAINT SKYBLUE (-7705 3575);
FORCEPROP 1 LAST TOLERANCE 1%
J 0
(-7705 3525);
DISPLAY 0.617021 (-7705 3525);
PAINT SKYBLUE (-7705 3525);
FORCEPROP 1 LAST PART_NUMBER G21796-026
J 0
(-7710 3375);
DISPLAY 0.617021 (-7710 3375);
PAINT BLUE (-7710 3375);
FORCEPROP 1 LAST MATERIAL CHIP
J 0
(-7710 3425);
DISPLAY 0.617021 (-7710 3425);
PAINT SKYBLUE (-7710 3425);
FORCEPROP 1 LAST WATTAGE 1/16W
J 0
(-7710 3475);
DISPLAY 0.617021 (-7710 3475);
PAINT SKYBLUE (-7710 3475);
FORCEPROP 1 LAST PACK_TYPE 0402
J 0
(-7710 3325);
DISPLAY 0.617021 (-7710 3325);
PAINT SKYBLUE (-7710 3325);
FORCEPROP 1 LASTPIN (-7750 3600) $PN 1
J 0
(-7745 3562);
DISPLAY 0.787234 (-7745 3562);
PAINT ORANGE (-7745 3562);
FORCEPROP 1 LASTPIN (-7750 3400) $PN 2
J 0
(-7745 3410);
DISPLAY 0.787234 (-7745 3410);
PAINT ORANGE (-7745 3410);
FORCEPROP 2 LAST ROOM CPLD
J 0
(-7700 3675);
DISPLAY 1.021277 (-7700 3675);
PAINT ORANGE (-7700 3675);
DISPLAY INVISIBLE (-7700 3675);
FORCEPROP 1 LAST PATH I59
J 0
(-7700 3675);
DISPLAY 0.978723 (-7700 3675);
PAINT WHITE (-7700 3675);
DISPLAY INVISIBLE (-7700 3675);
FORCEPROP 2 LAST BOM_COST CPLD
J 0
(-7700 3725);
DISPLAY 1.021277 (-7700 3725);
PAINT ORANGE (-7700 3725);
DISPLAY INVISIBLE (-7700 3725);
FORCEPROP 2 LAST CDS_LIB mstr_discrete
J 0
(-7750 3500);
PAINT ORANGE (-7750 3500);
DISPLAY INVISIBLE (-7750 3500);
FORCEPROP 2 LAST SEC 1
J 0
(-7700 3725);
PAINT MONO (-7700 3725);
DISPLAY INVISIBLE (-7700 3725);
FORCEPROP 2 LAST SEC_TYPE 0402
J 0
(-7700 3725);
DISPLAY 1.021277 (-7700 3725);
PAINT ORANGE (-7700 3725);
DISPLAY INVISIBLE (-7700 3725);
FORCEADD CAP_A..1
(-2650 1975);
FORCEPROP 1 LAST LOCATION C3P43
J 0
(-2600 2075);
DISPLAY 0.617021 (-2600 2075);
PAINT AQUA (-2600 2075);
FORCEPROP 1 LAST PART_NUMBER A36096-030
J 0
(-2600 1825);
DISPLAY 0.617021 (-2600 1825);
PAINT BLUE (-2600 1825);
FORCEPROP 1 LAST VALUE 0.1UF
J 0
(-2600 2025);
DISPLAY 0.617021 (-2600 2025);
PAINT SKYBLUE (-2600 2025);
FORCEPROP 1 LAST TOLERANCE 10%
J 0
(-2600 1925);
DISPLAY 0.617021 (-2600 1925);
PAINT SKYBLUE (-2600 1925);
FORCEPROP 1 LAST PACK_TYPE 0402V
J 0
(-2600 1775);
DISPLAY 0.617021 (-2600 1775);
PAINT SKYBLUE (-2600 1775);
FORCEPROP 1 LAST VOLTAGE 16V
J 0
(-2600 1975);
DISPLAY 0.617021 (-2600 1975);
PAINT SKYBLUE (-2600 1975);
FORCEPROP 1 LAST MATERIAL X7R
J 0
(-2600 1875);
DISPLAY 0.617021 (-2600 1875);
PAINT SKYBLUE (-2600 1875);
FORCEPROP 1 LASTPIN (-2650 2075) $PN 1
J 0
(-2640 2055);
DISPLAY 0.617021 (-2640 2055);
PAINT ORANGE (-2640 2055);
FORCEPROP 1 LASTPIN (-2650 1875) $PN 2
J 0
(-2640 1855);
DISPLAY 0.617021 (-2640 1855);
PAINT ORANGE (-2640 1855);
FORCEPROP 2 LAST ROOM CPLD
J 0
(-2600 2125);
DISPLAY 1.361702 (-2600 2125);
PAINT ORANGE (-2600 2125);
DISPLAY INVISIBLE (-2600 2125);
FORCEPROP 2 LAST $SEC 1
J 0
(-2600 2175);
PAINT MONO (-2600 2175);
DISPLAY INVISIBLE (-2600 2175);
FORCEPROP 2 LAST CDS_SEC 1
J 0
(-2600 2175);
PAINT MONO (-2600 2175);
DISPLAY INVISIBLE (-2600 2175);
FORCEPROP 2 LAST BOM_COST CPLD
J 0
(-2600 2175);
DISPLAY 1.361702 (-2600 2175);
PAINT ORANGE (-2600 2175);
DISPLAY INVISIBLE (-2600 2175);
FORCEPROP 2 LAST SIGNAL_MODEL DEFAULT_CAPACITOR_100000pF_2_1
J 0
(-2600 2175);
PAINT MONO (-2600 2175);
DISPLAY INVISIBLE (-2600 2175);
FORCEPROP 2 LAST CDS_LOCATION C3P43
J 0
(-2600 2075);
DISPLAY 0.617021 (-2600 2075);
PAINT AQUA (-2600 2075);
DISPLAY INVISIBLE (-2600 2075);
FORCEPROP 1 LAST PATH I6
J 0
(-2600 2125);
DISPLAY 0.978723 (-2600 2125);
PAINT WHITE (-2600 2125);
DISPLAY INVISIBLE (-2600 2125);
FORCEPROP 2 LAST CDS_LIB dev_discrete
J 0
(-2650 1975);
PAINT ORANGE (-2650 1975);
DISPLAY INVISIBLE (-2650 1975);
FORCEADD OFFPAGE..2
(-5100 3700);
FORCEPROP 2 LASTPIN (-5150 3700) SIG_NAME FM_MEM_EVENT_FUNC
J 2
(-5160 3710);
DISPLAY 0.617021 (-5160 3710);
PAINT ORANGE (-5160 3710);
FORCEPROP 2 LAST $XR0 190 
J 0
(-4911 3700);
DISPLAY 0.638298 (-4911 3700);
PAINT MONO (-4911 3700);
FORCEPROP 2 LAST CDS_LIB mstr_standard
J 0
(-5100 3700);
PAINT ORANGE (-5100 3700);
DISPLAY INVISIBLE (-5100 3700);
FORCEPROP 2 LAST PATH I60
J 0
(-4925 3775);
DISPLAY 1.021277 (-4925 3775);
PAINT ORANGE (-4925 3775);
DISPLAY INVISIBLE (-4925 3775);
FORCEPROP 1 LAST OFFPAGE TRUE
J 0
(-4775 3575);
DISPLAY 0.872340 (-4775 3575);
PAINT GREEN (-4775 3575);
DISPLAY INVISIBLE (-4775 3575);
FORCEPROP 1 LAST COMMENT_BODY TRUE
J 0
(-5145 3605);
DISPLAY 0.872340 (-5145 3605);
PAINT GREEN (-5145 3605);
DISPLAY INVISIBLE (-5145 3605);
FORCEADD GND..1
(-7750 3300);
FORCEPROP 3 LASTPIN (-7750 3350) SIG_NAME GND\g
J 0
(-7740 3360);
DISPLAY 0.659574 (-7740 3360);
PAINT MONO (-7740 3360);
DISPLAY INVISIBLE (-7740 3360);
FORCEPROP 1 LAST VOLTAGE 0.0V
J 0
(-7795 3257);
DISPLAY 0.340426 (-7795 3257);
PAINT SKYBLUE (-7795 3257);
DISPLAY INVISIBLE (-7795 3257);
FORCEPROP 1 LAST PATH I61
J 0
(-7675 3300);
DISPLAY 0.872340 (-7675 3300);
PAINT AQUA (-7675 3300);
DISPLAY INVISIBLE (-7675 3300);
FORCEPROP 1 LAST SIZE 1B
J 0
(-7675 3250);
DISPLAY 0.872340 (-7675 3250);
PAINT AQUA (-7675 3250);
DISPLAY INVISIBLE (-7675 3250);
FORCEPROP 2 LAST CDS_LIB mstr_symbols
J 0
(-7750 3300);
PAINT ORANGE (-7750 3300);
DISPLAY INVISIBLE (-7750 3300);
FORCEPROP 1 LAST BODY_TYPE PLUMBING
J 0
(-7795 3257);
DISPLAY 0.340426 (-7795 3257);
PAINT GREEN (-7795 3257);
DISPLAY INVISIBLE (-7795 3257);
FORCEPROP 1 LAST HDL_POWER GND
J 0
(-7750 3450);
DISPLAY 0.872340 (-7750 3450);
PAINT GREEN (-7750 3450);
DISPLAY INVISIBLE (-7750 3450);
FORCEADD PVPP_KLM..1
(-5750 3000);
FORCEPROP 3 LASTPIN (-5750 2950) SIG_NAME PVPP_KLM\g
J 0
(-5740 2960);
DISPLAY 0.659574 (-5740 2960);
PAINT MONO (-5740 2960);
DISPLAY INVISIBLE (-5740 2960);
FORCEPROP 1 LAST VOLTAGE 2.5V
J 0
(-5795 2957);
DISPLAY 0.340426 (-5795 2957);
PAINT SKYBLUE (-5795 2957);
DISPLAY INVISIBLE (-5795 2957);
FORCEPROP 2 LAST ROOM PVPP_KLM_VR
J 0
(-5500 3100);
PAINT ORANGE (-5500 3100);
DISPLAY INVISIBLE (-5500 3100);
FORCEPROP 2 LAST BOM_COST PVPP_KLM_VR
J 0
(-5675 3100);
PAINT MONO (-5675 3100);
DISPLAY INVISIBLE (-5675 3100);
FORCEPROP 1 LAST PATH I62
J 0
(-5700 3025);
DISPLAY 0.872340 (-5700 3025);
PAINT AQUA (-5700 3025);
DISPLAY INVISIBLE (-5700 3025);
FORCEPROP 2 LAST CDS_LIB mstr_symbols
J 0
(-5750 3000);
PAINT ORANGE (-5750 3000);
DISPLAY INVISIBLE (-5750 3000);
FORCEPROP 1 LAST BODY_TYPE PLUMBING
J 0
(-5795 2957);
DISPLAY 0.340426 (-5795 2957);
PAINT GREEN (-5795 2957);
DISPLAY INVISIBLE (-5795 2957);
FORCEPROP 1 LAST HDL_POWER PVPP_KLM
J 1
(-5750 3050);
DISPLAY 0.872340 (-5750 3050);
PAINT GREEN (-5750 3050);
DISPLAY INVISIBLE (-5750 3050);
FORCEADD CAP_A..1
(-3125 1975);
FORCEPROP 1 LAST LOCATION C3R3
J 0
(-3075 2075);
DISPLAY 0.617021 (-3075 2075);
PAINT AQUA (-3075 2075);
FORCEPROP 1 LAST PART_NUMBER A36096-030
J 0
(-3075 1825);
DISPLAY 0.617021 (-3075 1825);
PAINT BLUE (-3075 1825);
FORCEPROP 1 LAST VALUE 0.1UF
J 0
(-3075 2025);
DISPLAY 0.617021 (-3075 2025);
PAINT SKYBLUE (-3075 2025);
FORCEPROP 1 LAST TOLERANCE 10%
J 0
(-3075 1925);
DISPLAY 0.617021 (-3075 1925);
PAINT SKYBLUE (-3075 1925);
FORCEPROP 1 LAST PACK_TYPE 0402V
J 0
(-3075 1775);
DISPLAY 0.617021 (-3075 1775);
PAINT SKYBLUE (-3075 1775);
FORCEPROP 1 LAST VOLTAGE 16V
J 0
(-3075 1975);
DISPLAY 0.617021 (-3075 1975);
PAINT SKYBLUE (-3075 1975);
FORCEPROP 1 LAST MATERIAL X7R
J 0
(-3075 1875);
DISPLAY 0.617021 (-3075 1875);
PAINT SKYBLUE (-3075 1875);
FORCEPROP 1 LASTPIN (-3125 2075) $PN 1
J 0
(-3115 2055);
DISPLAY 0.617021 (-3115 2055);
PAINT ORANGE (-3115 2055);
FORCEPROP 1 LASTPIN (-3125 1875) $PN 2
J 0
(-3115 1855);
DISPLAY 0.617021 (-3115 1855);
PAINT ORANGE (-3115 1855);
FORCEPROP 2 LAST ROOM CPLD
J 0
(-3075 2125);
DISPLAY 1.361702 (-3075 2125);
PAINT ORANGE (-3075 2125);
DISPLAY INVISIBLE (-3075 2125);
FORCEPROP 2 LAST SIGNAL_MODEL DEFAULT_CAPACITOR_100000pF_2_1
J 0
(-3075 2175);
PAINT MONO (-3075 2175);
DISPLAY INVISIBLE (-3075 2175);
FORCEPROP 2 LAST BOM_COST CPLD
J 0
(-3075 2175);
DISPLAY 1.361702 (-3075 2175);
PAINT ORANGE (-3075 2175);
DISPLAY INVISIBLE (-3075 2175);
FORCEPROP 2 LAST CDS_SEC 1
J 0
(-3075 2175);
PAINT MONO (-3075 2175);
DISPLAY INVISIBLE (-3075 2175);
FORCEPROP 2 LAST $SEC 1
J 0
(-3075 2175);
PAINT MONO (-3075 2175);
DISPLAY INVISIBLE (-3075 2175);
FORCEPROP 1 LAST PATH I7
J 0
(-3075 2125);
DISPLAY 0.978723 (-3075 2125);
PAINT WHITE (-3075 2125);
DISPLAY INVISIBLE (-3075 2125);
FORCEPROP 2 LAST CDS_LOCATION C3R3
J 0
(-3075 2075);
DISPLAY 0.617021 (-3075 2075);
PAINT AQUA (-3075 2075);
DISPLAY INVISIBLE (-3075 2075);
FORCEPROP 2 LAST CDS_LIB dev_discrete
J 0
(-3125 1975);
PAINT ORANGE (-3125 1975);
DISPLAY INVISIBLE (-3125 1975);
FORCEADD CAP_A..1
(-3150 1300);
FORCEPROP 1 LAST LOCATION C2R1
J 0
(-3100 1400);
DISPLAY 0.617021 (-3100 1400);
PAINT AQUA (-3100 1400);
FORCEPROP 1 LAST PART_NUMBER A36096-030
J 0
(-3100 1150);
DISPLAY 0.617021 (-3100 1150);
PAINT BLUE (-3100 1150);
FORCEPROP 1 LAST VALUE 0.1UF
J 0
(-3100 1350);
DISPLAY 0.617021 (-3100 1350);
PAINT SKYBLUE (-3100 1350);
FORCEPROP 1 LAST TOLERANCE 10%
J 0
(-3100 1250);
DISPLAY 0.617021 (-3100 1250);
PAINT SKYBLUE (-3100 1250);
FORCEPROP 1 LAST PACK_TYPE 0402V
J 0
(-3100 1100);
DISPLAY 0.617021 (-3100 1100);
PAINT SKYBLUE (-3100 1100);
FORCEPROP 1 LAST VOLTAGE 16V
J 0
(-3100 1300);
DISPLAY 0.617021 (-3100 1300);
PAINT SKYBLUE (-3100 1300);
FORCEPROP 1 LAST MATERIAL X7R
J 0
(-3100 1200);
DISPLAY 0.617021 (-3100 1200);
PAINT SKYBLUE (-3100 1200);
FORCEPROP 1 LASTPIN (-3150 1400) $PN 1
J 0
(-3140 1380);
DISPLAY 0.617021 (-3140 1380);
PAINT ORANGE (-3140 1380);
FORCEPROP 1 LASTPIN (-3150 1200) $PN 2
J 0
(-3140 1180);
DISPLAY 0.617021 (-3140 1180);
PAINT ORANGE (-3140 1180);
FORCEPROP 2 LAST ROOM CPLD
J 0
(-3100 1450);
DISPLAY 1.361702 (-3100 1450);
PAINT ORANGE (-3100 1450);
DISPLAY INVISIBLE (-3100 1450);
FORCEPROP 2 LAST $SEC 1
J 0
(-3100 1500);
DISPLAY 0.914894 (-3100 1500);
PAINT MONO (-3100 1500);
DISPLAY INVISIBLE (-3100 1500);
FORCEPROP 2 LAST CDS_SEC 1
J 0
(-3100 1500);
DISPLAY 1.361702 (-3100 1500);
PAINT ORANGE (-3100 1500);
DISPLAY INVISIBLE (-3100 1500);
FORCEPROP 2 LAST BOM_COST CPLD
J 0
(-3100 1500);
DISPLAY 1.361702 (-3100 1500);
PAINT ORANGE (-3100 1500);
DISPLAY INVISIBLE (-3100 1500);
FORCEPROP 2 LAST SIGNAL_MODEL DEFAULT_CAPACITOR_100000pF_2_1
J 0
(-3100 1500);
PAINT MONO (-3100 1500);
DISPLAY INVISIBLE (-3100 1500);
FORCEPROP 2 LAST CDS_LIB dev_discrete
J 0
(-3150 1300);
PAINT ORANGE (-3150 1300);
DISPLAY INVISIBLE (-3150 1300);
FORCEPROP 2 LAST CDS_LOCATION C2R1
J 0
(-3100 1400);
DISPLAY 0.617021 (-3100 1400);
PAINT AQUA (-3100 1400);
DISPLAY INVISIBLE (-3100 1400);
FORCEPROP 1 LAST PATH I8
J 0
(-3100 1450);
DISPLAY 0.978723 (-3100 1450);
PAINT WHITE (-3100 1450);
DISPLAY INVISIBLE (-3100 1450);
FORCEADD CAP_A..1
(-3600 1975);
FORCEPROP 1 LAST LOCATION C2P2
J 0
(-3550 2075);
DISPLAY 0.617021 (-3550 2075);
PAINT AQUA (-3550 2075);
FORCEPROP 1 LAST PART_NUMBER A36096-030
J 0
(-3550 1825);
DISPLAY 0.617021 (-3550 1825);
PAINT BLUE (-3550 1825);
FORCEPROP 1 LAST VALUE 0.1UF
J 0
(-3550 2025);
DISPLAY 0.617021 (-3550 2025);
PAINT SKYBLUE (-3550 2025);
FORCEPROP 1 LAST TOLERANCE 10%
J 0
(-3550 1925);
DISPLAY 0.617021 (-3550 1925);
PAINT SKYBLUE (-3550 1925);
FORCEPROP 1 LAST PACK_TYPE 0402V
J 0
(-3550 1775);
DISPLAY 0.617021 (-3550 1775);
PAINT SKYBLUE (-3550 1775);
FORCEPROP 1 LAST VOLTAGE 16V
J 0
(-3550 1975);
DISPLAY 0.617021 (-3550 1975);
PAINT SKYBLUE (-3550 1975);
FORCEPROP 1 LAST MATERIAL X7R
J 0
(-3550 1875);
DISPLAY 0.617021 (-3550 1875);
PAINT SKYBLUE (-3550 1875);
FORCEPROP 1 LASTPIN (-3600 2075) $PN 1
J 0
(-3590 2055);
DISPLAY 0.617021 (-3590 2055);
PAINT ORANGE (-3590 2055);
FORCEPROP 1 LASTPIN (-3600 1875) $PN 2
J 0
(-3590 1855);
DISPLAY 0.617021 (-3590 1855);
PAINT ORANGE (-3590 1855);
FORCEPROP 2 LAST ROOM CPLD
J 0
(-3550 2125);
DISPLAY 1.361702 (-3550 2125);
PAINT ORANGE (-3550 2125);
DISPLAY INVISIBLE (-3550 2125);
FORCEPROP 2 LAST $SEC 1
J 0
(-3550 2175);
PAINT MONO (-3550 2175);
DISPLAY INVISIBLE (-3550 2175);
FORCEPROP 2 LAST CDS_SEC 1
J 0
(-3550 2175);
PAINT MONO (-3550 2175);
DISPLAY INVISIBLE (-3550 2175);
FORCEPROP 2 LAST BOM_COST CPLD
J 0
(-3550 2175);
DISPLAY 1.361702 (-3550 2175);
PAINT ORANGE (-3550 2175);
DISPLAY INVISIBLE (-3550 2175);
FORCEPROP 2 LAST SIGNAL_MODEL DEFAULT_CAPACITOR_100000pF_2_1
J 0
(-3550 2175);
PAINT MONO (-3550 2175);
DISPLAY INVISIBLE (-3550 2175);
FORCEPROP 2 LAST CDS_LOCATION C2P2
J 0
(-3550 2075);
DISPLAY 0.617021 (-3550 2075);
PAINT AQUA (-3550 2075);
DISPLAY INVISIBLE (-3550 2075);
FORCEPROP 1 LAST PATH I9
J 0
(-3550 2125);
DISPLAY 0.978723 (-3550 2125);
PAINT WHITE (-3550 2125);
DISPLAY INVISIBLE (-3550 2125);
FORCEPROP 2 LAST CDS_LIB dev_discrete
J 0
(-3600 1975);
PAINT ORANGE (-3600 1975);
DISPLAY INVISIBLE (-3600 1975);
FORCEADD DNS..2
(-7345 4395);
PAINT RED (-7345 4395);
FORCEPROP 1 LAST COMMENT_BODY TRUE
R 1
J 0
(-7270 4170);
DISPLAY 0.872340 (-7270 4170);
PAINT GREEN (-7270 4170);
DISPLAY INVISIBLE (-7270 4170);
FORCEPROP 2 LAST CDS_LIB mstr_misc
J 0
(-7345 4395);
DISPLAY INVISIBLE (-7345 4395);
FORCEADD INTEL_CORP_BPAGE..1
(0 0);
FORCEPROP 1 LAST CDS_CON_LAST_MODIFIED Fri Jun 16 17:49:11 2017
J 0
(-1425 325);
PAINT ORANGE (-1425 325);
DISPLAY INVISIBLE (-1425 325);
FORCEPROP 1 LAST CUSTOM_TXT_CDS <CURRENT_DESIGN_SHEET> OF <TOTAL_DESIGN_SHEETS>
J 0
(-500 25);
PAINT ORANGE (-500 25);
FORCEPROP 1 LAST CUSTOM_TXT_CDS <CON_LAST_MODIFIED>
J 0
(-4000 100);
PAINT ORANGE (-4000 100);
FORCEPROP 2 LAST CUSTOM_TXT_CDS <XR_PAGE_TITLE>
J 0
(-7890 5250);
DISPLAY 0.638298 (-7890 5250);
PAINT PINK (-7890 5250);
DISPLAY INVISIBLE (-7890 5250);
FORCEPROP 1 LAST SCH_TITLE CPLD (3 OF 3)
J 0
(-7950 50);
DISPLAY 1.212766 (-7950 50);
PAINT ORANGE (-7950 50);
FORCEPROP 2 LAST CDS_LIB mstr_symbols
J 0
(0 0);
PAINT ORANGE (0 0);
DISPLAY INVISIBLE (0 0);
FORCEPROP 2 LAST PAGE_BORDER TRUE
J 0
(-7890 5250);
DISPLAY 0.638298 (-7890 5250);
PAINT PINK (-7890 5250);
DISPLAY INVISIBLE (-7890 5250);
FORCEPROP 1 LAST COMMENT_BODY TRUE
J 0
(12 12);
DISPLAY 0.468085 (12 12);
PAINT GREEN (12 12);
DISPLAY INVISIBLE (12 12);
FORCEPROP 2 LAST CDS_XR_PAGE_TITLE CR-192 : @BASEBOARD_FAB2_LIB.BASEBOARD_FAB2(SCH_1):PAGE192
J 0
(-7890 5250);
DISPLAY 0.638298 (-7890 5250);
PAINT PINK (-7890 5250);
DISPLAY INVISIBLE (-7890 5250);
FORCEADD DNS..2
(-7745 4395);
PAINT RED (-7745 4395);
FORCEPROP 2 LAST CDS_LIB mstr_misc
J 0
(-7745 4395);
PAINT ORANGE (-7745 4395);
DISPLAY INVISIBLE (-7745 4395);
FORCEPROP 1 LAST COMMENT_BODY TRUE
R 1
J 0
(-7670 4170);
DISPLAY 0.872340 (-7670 4170);
PAINT GREEN (-7670 4170);
DISPLAY INVISIBLE (-7670 4170);
WIRE 16 -1 (-1225 1725)(-1225 1675);
WIRE 16 -1 (-1225 1725)(-1700 1725);
WIRE 16 -1 (-1225 1875)(-1225 1725);
WIRE 16 -1 (-1700 1725)(-2175 1725);
WIRE 16 -1 (-1700 1875)(-1700 1725);
WIRE 16 -1 (-2175 1725)(-2650 1725);
WIRE 16 -1 (-2175 1875)(-2175 1725);
WIRE 16 -1 (-2650 1725)(-3125 1725);
WIRE 16 -1 (-2650 1875)(-2650 1725);
WIRE 16 -1 (-3125 1725)(-3600 1725);
WIRE 16 -1 (-3125 1875)(-3125 1725);
WIRE 16 -1 (-3600 1725)(-4075 1725);
WIRE 16 -1 (-3600 1725)(-3600 1875);
WIRE 16 -1 (-4075 1725)(-4550 1725);
WIRE 16 -1 (-4075 1875)(-4075 1725);
WIRE 16 -1 (-4550 1725)(-5025 1725);
WIRE 16 -1 (-4550 1875)(-4550 1725);
WIRE 16 -1 (-5025 1725)(-5500 1725);
WIRE 16 -1 (-5025 1875)(-5025 1725);
WIRE 16 -1 (-5975 1725)(-5500 1725);
WIRE 16 -1 (-5500 1875)(-5500 1725);
WIRE 16 -1 (-6450 1725)(-5975 1725);
WIRE 16 -1 (-5975 1875)(-5975 1725);
WIRE 16 -1 (-6925 1725)(-6450 1725);
WIRE 16 -1 (-6450 1875)(-6450 1725);
WIRE 16 -1 (-6925 1875)(-6925 1725);
WIRE 16 -1 (-6475 1100)(-6475 1050);
WIRE 16 -1 (-6475 1100)(-6250 1100);
WIRE 16 -1 (-6850 1100)(-6475 1100);
WIRE 16 -1 (-6850 1200)(-6850 1100);
WIRE 16 -1 (-5700 1100)(-6250 1100);
WIRE 16 -1 (-6250 1200)(-6250 1100);
WIRE 16 -1 (-5225 1100)(-5700 1100);
WIRE 16 -1 (-5700 1200)(-5700 1100);
WIRE 16 -1 (-4725 1100)(-5225 1100);
WIRE 16 -1 (-5225 1200)(-5225 1100);
WIRE 16 -1 (-4200 1100)(-4725 1100);
WIRE 16 -1 (-4725 1200)(-4725 1100);
WIRE 16 -1 (-3700 1100)(-4200 1100);
WIRE 16 -1 (-4200 1200)(-4200 1100);
WIRE 16 -1 (-3150 1100)(-3700 1100);
WIRE 16 -1 (-3700 1200)(-3700 1100);
WIRE 16 -1 (-3150 1200)(-3150 1100);
WIRE 16 -1 (-2500 4650)(-2500 4500);
WIRE 16 -1 (-2500 4500)(-2500 4450);
WIRE 16 -1 (-2500 4500)(-2300 4500);
WIRE 16 -1 (-2500 4450)(-2500 4400);
WIRE 16 -1 (-2500 4450)(-2300 4450);
WIRE 16 -1 (-2500 4400)(-2500 4350);
WIRE 16 -1 (-2500 4400)(-2300 4400);
WIRE 16 -1 (-2500 4350)(-2500 4300);
WIRE 16 -1 (-2500 4350)(-2300 4350);
WIRE 16 -1 (-2500 4300)(-2500 4250);
WIRE 16 -1 (-2500 4300)(-2300 4300);
WIRE 16 -1 (-2500 4250)(-2500 4200);
WIRE 16 -1 (-2500 4250)(-2300 4250);
WIRE 16 -1 (-2500 4200)(-2500 4150);
WIRE 16 -1 (-2500 4200)(-2300 4200);
WIRE 16 -1 (-2500 4150)(-2500 4050);
WIRE 16 -1 (-2500 4150)(-2300 4150);
WIRE 16 -1 (-2500 4050)(-2500 4000);
WIRE 16 -1 (-2500 4050)(-2300 4050);
WIRE 16 -1 (-2500 4000)(-2500 3950);
WIRE 16 -1 (-2500 4000)(-2300 4000);
WIRE 16 -1 (-2500 3950)(-2500 3900);
WIRE 16 -1 (-2500 3950)(-2300 3950);
WIRE 16 -1 (-2500 3900)(-2500 3850);
WIRE 16 -1 (-2500 3900)(-2300 3900);
WIRE 16 -1 (-2500 3850)(-2500 3800);
WIRE 16 -1 (-2500 3850)(-2300 3850);
WIRE 16 -1 (-2500 3800)(-2500 3750);
WIRE 16 -1 (-2500 3800)(-2300 3800);
WIRE 16 -1 (-2500 3750)(-2500 3700);
WIRE 16 -1 (-2500 3750)(-2300 3750);
WIRE 16 -1 (-2500 3700)(-2500 3650);
WIRE 16 -1 (-2500 3700)(-2300 3700);
WIRE 16 -1 (-2500 3650)(-2500 3600);
WIRE 16 -1 (-2500 3650)(-2300 3650);
WIRE 16 -1 (-2500 3600)(-2500 3550);
WIRE 16 -1 (-2500 3600)(-2300 3600);
WIRE 16 -1 (-2500 3550)(-2500 3500);
WIRE 16 -1 (-2300 3550)(-2500 3550);
WIRE 16 -1 (-2500 3500)(-2500 3450);
WIRE 16 -1 (-2300 3500)(-2500 3500);
WIRE 16 -1 (-2500 3450)(-2500 3400);
WIRE 16 -1 (-2500 3450)(-2300 3450);
WIRE 16 -1 (-2500 3400)(-2500 3350);
WIRE 16 -1 (-2500 3400)(-2300 3400);
WIRE 16 -1 (-2500 3350)(-2500 3300);
WIRE 16 -1 (-2500 3350)(-2300 3350);
WIRE 16 -1 (-2500 3300)(-2300 3300);
WIRE 16 -1 (-6925 2225)(-6925 2175);
WIRE 16 -1 (-6925 2175)(-6450 2175);
WIRE 16 -1 (-6925 2075)(-6925 2175);
WIRE 16 -1 (-6450 2175)(-5975 2175);
WIRE 16 -1 (-6450 2075)(-6450 2175);
WIRE 16 -1 (-5975 2175)(-5500 2175);
WIRE 16 -1 (-5975 2075)(-5975 2175);
WIRE 16 -1 (-5500 2175)(-5025 2175);
WIRE 16 -1 (-5500 2075)(-5500 2175);
WIRE 16 -1 (-4550 2175)(-5025 2175);
WIRE 16 -1 (-5025 2075)(-5025 2175);
WIRE 16 -1 (-4550 2175)(-4075 2175);
WIRE 16 -1 (-4550 2075)(-4550 2175);
WIRE 16 -1 (-4075 2175)(-3600 2175);
WIRE 16 -1 (-4075 2075)(-4075 2175);
WIRE 16 -1 (-3600 2175)(-3125 2175);
WIRE 16 -1 (-3600 2075)(-3600 2175);
WIRE 16 -1 (-3125 2175)(-2650 2175);
WIRE 16 -1 (-3125 2075)(-3125 2175);
WIRE 16 -1 (-2650 2175)(-2175 2175);
WIRE 16 -1 (-2650 2075)(-2650 2175);
WIRE 16 -1 (-2175 2175)(-1700 2175);
WIRE 16 -1 (-2175 2075)(-2175 2175);
WIRE 16 -1 (-1225 2175)(-1700 2175);
WIRE 16 -1 (-1700 2075)(-1700 2175);
WIRE 16 -1 (-1225 2075)(-1225 2175);
WIRE 16 -1 (-6850 1475)(-6850 1450);
WIRE 16 -1 (-6850 1450)(-6250 1450);
WIRE 16 -1 (-6850 1400)(-6850 1450);
WIRE 16 -1 (-5700 1450)(-6250 1450);
WIRE 16 -1 (-6250 1400)(-6250 1450);
WIRE 16 -1 (-5225 1450)(-5700 1450);
WIRE 16 -1 (-5700 1400)(-5700 1450);
WIRE 16 -1 (-4725 1450)(-5225 1450);
WIRE 16 -1 (-5225 1400)(-5225 1450);
WIRE 16 -1 (-4200 1450)(-4725 1450);
WIRE 16 -1 (-4725 1400)(-4725 1450);
WIRE 16 -1 (-3700 1450)(-4200 1450);
WIRE 16 -1 (-4200 1400)(-4200 1450);
WIRE 16 -1 (-3150 1450)(-3700 1450);
WIRE 16 -1 (-3700 1400)(-3700 1450);
WIRE 16 -1 (-3150 1400)(-3150 1450);
WIRE 16 -1 (-6150 4500)(-6150 4550);
WIRE 16 -1 (-5750 4550)(-5750 4500);
WIRE 16 -1 (-6550 4500)(-6550 4550);
WIRE 16 -1 (-6950 4500)(-6950 4550);
WIRE 16 -1 (-1100 3250)(-1100 3150);
WIRE 16 -1 (-1100 3300)(-1100 3250);
WIRE 16 -1 (-1100 3250)(-1400 3250);
WIRE 16 -1 (-1100 3350)(-1100 3300);
WIRE 16 -1 (-1100 3300)(-1400 3300);
WIRE 16 -1 (-1100 3400)(-1100 3350);
WIRE 16 -1 (-1100 3350)(-1400 3350);
WIRE 16 -1 (-1100 3450)(-1100 3400);
WIRE 16 -1 (-1100 3400)(-1400 3400);
WIRE 16 -1 (-1100 3500)(-1100 3450);
WIRE 16 -1 (-1100 3450)(-1400 3450);
WIRE 16 -1 (-1100 3550)(-1100 3500);
WIRE 16 -1 (-1100 3500)(-1400 3500);
WIRE 16 -1 (-1100 3600)(-1100 3550);
WIRE 16 -1 (-1100 3550)(-1400 3550);
WIRE 16 -1 (-1100 3650)(-1100 3600);
WIRE 16 -1 (-1100 3600)(-1400 3600);
WIRE 16 -1 (-1100 3700)(-1100 3650);
WIRE 16 -1 (-1100 3650)(-1400 3650);
WIRE 16 -1 (-1100 3750)(-1100 3700);
WIRE 16 -1 (-1100 3700)(-1400 3700);
WIRE 16 -1 (-1100 3800)(-1100 3750);
WIRE 16 -1 (-1100 3750)(-1400 3750);
WIRE 16 -1 (-1100 3850)(-1100 3800);
WIRE 16 -1 (-1100 3800)(-1400 3800);
WIRE 16 -1 (-1100 3900)(-1100 3850);
WIRE 16 -1 (-1100 3850)(-1400 3850);
WIRE 16 -1 (-1100 3950)(-1100 3900);
WIRE 16 -1 (-1100 3900)(-1400 3900);
WIRE 16 -1 (-1100 4000)(-1100 3950);
WIRE 16 -1 (-1100 3950)(-1400 3950);
WIRE 16 -1 (-1100 4050)(-1100 4000);
WIRE 16 -1 (-1100 4000)(-1400 4000);
WIRE 16 -1 (-1100 4100)(-1100 4050);
WIRE 16 -1 (-1100 4050)(-1400 4050);
WIRE 16 -1 (-1100 4150)(-1100 4100);
WIRE 16 -1 (-1100 4100)(-1400 4100);
WIRE 16 -1 (-1100 4200)(-1100 4150);
WIRE 16 -1 (-1100 4150)(-1400 4150);
WIRE 16 -1 (-1100 4250)(-1100 4200);
WIRE 16 -1 (-1400 4200)(-1100 4200);
WIRE 16 -1 (-1100 4300)(-1100 4250);
WIRE 16 -1 (-1100 4250)(-1400 4250);
WIRE 16 -1 (-1100 4350)(-1100 4300);
WIRE 16 -1 (-1100 4300)(-1400 4300);
WIRE 16 -1 (-1100 4400)(-1100 4350);
WIRE 16 -1 (-1100 4350)(-1400 4350);
WIRE 16 -1 (-1100 4400)(-1400 4400);
WIRE 16 -1 (-6150 2950)(-6150 2900);
WIRE 16 -1 (-7350 4550)(-7350 4500);
WIRE 16 -1 (-7750 4500)(-7750 4550);
WIRE 16 -1 (-7750 3400)(-7750 3350);
WIRE 16 -1 (-5750 2950)(-5750 2900);
WIRE 16 273 (-7400 3550)(-7400 3300);
WIRE 16 273 (-4700 3550)(-7400 3550);
WIRE 16 273 (-7400 3300)(-4700 3300);
WIRE 16 273 (-4700 3300)(-4700 3550);
WIRE 16 -1 (-7750 3700)(-7750 3600);
WIRE 16 -1 (-7750 3700)(-5150 3700);
WIRE 16 -1 (-7750 4300)(-7750 3700);
WIRE 16 -1 (-6550 4000)(-5150 4000);
WIRE 16 -1 (-6550 4300)(-6550 4000);
WIRE 16 -1 (-6950 3900)(-5150 3900);
WIRE 16 -1 (-6950 4300)(-6950 3900);
WIRE 16 -1 (-7350 3800)(-7350 4300);
WIRE 16 -1 (-5150 3800)(-7350 3800);
WIRE 16 -1 (-5750 2700)(-5750 2600);
WIRE 16 -1 (-5750 2600)(-5150 2600);
WIRE 16 -1 (-6150 2700)(-6150 2500);
WIRE 16 -1 (-6150 2500)(-5150 2500);
WIRE 16 -1 (-6150 4300)(-6150 4100);
WIRE 16 -1 (-6150 4100)(-5150 4100);
WIRE 16 -1 (-5750 4300)(-5750 4200);
WIRE 16 -1 (-5750 4200)(-5150 4200);
WIRE 3 682 (-1300 4550)(-1200 4550);
DOT 1 (-1100 4350);
DOT 1 (-1100 4300);
DOT 1 (-1100 4000);
DOT 1 (-6850 1450);
DOT 1 (-6475 1100);
DOT 1 (-6250 1100);
DOT 1 (-6250 1450);
DOT 1 (-6450 1725);
DOT 1 (-7750 3700);
DOT 1 (-6925 2175);
DOT 1 (-6450 2175);
DOT 1 (-5700 1100);
DOT 1 (-5700 1450);
DOT 1 (-5975 1725);
DOT 1 (-5225 1100);
DOT 1 (-5225 1450);
DOT 1 (-5500 1725);
DOT 1 (-4725 1100);
DOT 1 (-4725 1450);
DOT 1 (-5025 1725);
DOT 1 (-4200 1100);
DOT 1 (-4200 1450);
DOT 1 (-4550 1725);
DOT 1 (-5975 2175);
DOT 1 (-5500 2175);
DOT 1 (-5025 2175);
DOT 1 (-4550 2175);
DOT 1 (-3700 1100);
DOT 1 (-3700 1450);
DOT 1 (-4075 1725);
DOT 1 (-3600 1725);
DOT 1 (-3125 1725);
DOT 1 (-2650 1725);
DOT 1 (-2175 1725);
DOT 1 (-4075 2175);
DOT 1 (-3600 2175);
DOT 1 (-3125 2175);
DOT 1 (-2650 2175);
DOT 1 (-2175 2175);
DOT 1 (-2500 3350);
DOT 1 (-2500 3450);
DOT 1 (-2500 3500);
DOT 1 (-2500 3550);
DOT 1 (-2500 3600);
DOT 1 (-2500 3650);
DOT 1 (-2500 3700);
DOT 1 (-2500 3750);
DOT 1 (-2500 3800);
DOT 1 (-2500 3850);
DOT 1 (-2500 3950);
DOT 1 (-2500 3900);
DOT 1 (-2500 4000);
DOT 1 (-2500 4050);
DOT 1 (-1700 1725);
DOT 1 (-1225 1725);
DOT 1 (-1700 2175);
DOT 1 (-1100 3250);
DOT 1 (-1100 3300);
DOT 1 (-1100 3400);
DOT 1 (-1100 3450);
DOT 1 (-1100 3550);
DOT 1 (-1100 3500);
DOT 1 (-1100 3600);
DOT 1 (-1100 3700);
DOT 1 (-1100 3650);
DOT 1 (-1100 3750);
DOT 1 (-1100 3800);
DOT 1 (-1100 3850);
DOT 1 (-1100 3900);
DOT 1 (-1100 3950);
DOT 1 (-1100 4050);
DOT 1 (-1100 4100);
DOT 1 (-2500 4150);
DOT 1 (-2500 4200);
DOT 1 (-2500 4250);
DOT 1 (-2500 4300);
DOT 1 (-2500 4350);
DOT 1 (-2500 4450);
DOT 1 (-2500 4400);
DOT 1 (-2500 4500);
DOT 1 (-1100 4200);
DOT 1 (-1100 4150);
DOT 1 (-1100 4250);
DOT 1 (-1100 3350);
DOT 1 (-2500 3400);
FORCENOTE
FM_MEM_EVENT_FUNC STATE:
(-7350 3475) 0;
DISPLAY LEFT (-7350 3475);
DISPLAY 0.851064 (-7350 3475);
PAINT PURPLE (-7350 3475);
FORCENOTE
ROOM CPLD
(-7875 425) 0;
DISPLAY LEFT (-7875 425);
DISPLAY 2.148936 (-7875 425);
PAINT PURPLE (-7875 425);
FORCENOTE
BOM_COST CPLD
(-7900 300) 0;
DISPLAY LEFT (-7900 300);
DISPLAY 2.148936 (-7900 300);
PAINT PURPLE (-7900 300);
FORCENOTE
HIGH:  MEM_EVENT ASSERTION ASSERTS THERMTRIP TO PCH THROUGH CPLD
(-7350 3325) 0;
DISPLAY LEFT (-7350 3325);
DISPLAY 0.851064 (-7350 3325);
PAINT PURPLE (-7350 3325);
FORCENOTE
LOW:    MEM_EVENT ASSERTION DOES NOT DRIVE THERMTRIP (NVDIMM MODE)
(-7350 3400) 0;
DISPLAY LEFT (-7350 3400);
DISPLAY 0.851064 (-7350 3400);
PAINT PURPLE (-7350 3400);
FORCENOTE
TP FAB1 DEL NET 0309
(-1150 4525) 0;
DISPLAY LEFT (-1150 4525);
DISPLAY 1.021277 (-1150 4525);
PAINT RED (-1150 4525);
FORCENOTE
TP FAB1 NOPOP R7E18 0523
(-7300 4100) 0;
DISPLAY LEFT (-7300 4100);
DISPLAY 1.021277 (-7300 4100);
PAINT RED (-7300 4100);
QUIT
